(kicad_sch
	(version 20250114)
	(generator "eeschema")
	(generator_version "9.0")
	(paper "A3")
	(title_block
		(title "COM Express 7 Baseboard")
		(date "2025-02-04")
		(rev "1.1.2")
		(company "Antmicro Ltd")
		(comment 1 "www.antmicro.com")
	)
	(text "PCIe clock fanout buffer"
		(exclude_from_sim no)
		(at 83.82 33.02 0)
		(effects
			(font
				(size 2 2)
				(thickness 0.8)
				(bold yes)
			)
			(justify left bottom)
		)
	)
	(text "SUSCLK generator"
		(exclude_from_sim no)
		(at 104.14 149.86 0)
		(effects
			(font
				(size 2 2)
				(thickness 0.4)
				(bold yes)
			)
			(justify left bottom)
		)
	)
	(junction
		(at 87.63 99.06)
		(diameter 0)
		(color 0 0 0 0)
	)
	(junction
		(at 60.96 83.82)
		(diameter 0)
		(color 0 0 0 0)
	)
	(junction
		(at 82.55 50.8)
		(diameter 0)
		(color 0 0 0 0)
	)
	(junction
		(at 73.66 50.8)
		(diameter 0)
		(color 0 0 0 0)
	)
	(junction
		(at 110.49 58.42)
		(diameter 0)
		(color 0 0 0 0)
	)
	(junction
		(at 91.44 50.8)
		(diameter 0)
		(color 0 0 0 0)
	)
	(junction
		(at 110.49 63.5)
		(diameter 0)
		(color 0 0 0 0)
	)
	(junction
		(at 80.01 91.44)
		(diameter 0)
		(color 0 0 0 0)
	)
	(junction
		(at 97.79 93.98)
		(diameter 0)
		(color 0 0 0 0)
	)
	(junction
		(at 100.33 50.8)
		(diameter 0)
		(color 0 0 0 0)
	)
	(junction
		(at 114.3 187.96)
		(diameter 0)
		(color 0 0 0 0)
	)
	(junction
		(at 110.49 66.04)
		(diameter 0)
		(color 0 0 0 0)
	)
	(junction
		(at 85.09 200.66)
		(diameter 0)
		(color 0 0 0 0)
	)
	(junction
		(at 123.19 213.36)
		(diameter 0)
		(color 0 0 0 0)
	)
	(junction
		(at 74.93 200.66)
		(diameter 0)
		(color 0 0 0 0)
	)
	(junction
		(at 45.72 50.8)
		(diameter 0)
		(color 0 0 0 0)
	)
	(junction
		(at 97.79 78.74)
		(diameter 0)
		(color 0 0 0 0)
	)
	(junction
		(at 54.61 50.8)
		(diameter 0)
		(color 0 0 0 0)
	)
	(junction
		(at 63.5 50.8)
		(diameter 0)
		(color 0 0 0 0)
	)
	(junction
		(at 123.19 215.9)
		(diameter 0)
		(color 0 0 0 0)
	)
	(junction
		(at 54.61 81.28)
		(diameter 0)
		(color 0 0 0 0)
	)
	(junction
		(at 143.51 114.3)
		(diameter 0)
		(color 0 0 0 0)
	)
	(junction
		(at 123.19 205.74)
		(diameter 0)
		(color 0 0 0 0)
	)
	(junction
		(at 110.49 60.96)
		(diameter 0)
		(color 0 0 0 0)
	)
	(junction
		(at 73.66 88.9)
		(diameter 0)
		(color 0 0 0 0)
	)
	(junction
		(at 67.31 86.36)
		(diameter 0)
		(color 0 0 0 0)
	)
	(no_connect
		(at 142.24 210.82)
	)
	(bus_entry
		(at 187.96 73.66)
		(size 1.27 1.27)
		(stroke
			(width 0)
			(type default)
		)
	)
	(bus_entry
		(at 81.28 76.2)
		(size -1.27 -1.27)
		(stroke
			(width 0)
			(type default)
		)
	)
	(bus_entry
		(at 187.96 76.2)
		(size 1.27 -1.27)
		(stroke
			(width 0)
			(type default)
		)
	)
	(bus_entry
		(at 187.96 91.44)
		(size 1.27 -1.27)
		(stroke
			(width 0)
			(type default)
		)
	)
	(bus_entry
		(at 187.96 83.82)
		(size 1.27 -1.27)
		(stroke
			(width 0)
			(type default)
		)
	)
	(bus_entry
		(at 187.96 66.04)
		(size 1.27 1.27)
		(stroke
			(width 0)
			(type default)
		)
	)
	(bus_entry
		(at 81.28 73.66)
		(size -1.27 1.27)
		(stroke
			(width 0)
			(type default)
		)
	)
	(bus_entry
		(at 187.96 60.96)
		(size 1.27 -1.27)
		(stroke
			(width 0)
			(type default)
		)
	)
	(bus_entry
		(at 187.96 68.58)
		(size 1.27 -1.27)
		(stroke
			(width 0)
			(type default)
		)
	)
	(bus_entry
		(at 187.96 58.42)
		(size 1.27 1.27)
		(stroke
			(width 0)
			(type default)
		)
	)
	(bus_entry
		(at 187.96 88.9)
		(size 1.27 1.27)
		(stroke
			(width 0)
			(type default)
		)
	)
	(bus_entry
		(at 187.96 81.28)
		(size 1.27 1.27)
		(stroke
			(width 0)
			(type default)
		)
	)
	(wire
		(pts
			(xy 45.72 81.28) (xy 54.61 81.28)
		)
		(stroke
			(width 0)
			(type default)
		)
	)
	(wire
		(pts
			(xy 171.45 66.04) (xy 168.91 68.58)
		)
		(stroke
			(width 0)
			(type default)
		)
	)
	(wire
		(pts
			(xy 73.66 50.8) (xy 82.55 50.8)
		)
		(stroke
			(width 0)
			(type default)
		)
	)
	(wire
		(pts
			(xy 110.49 58.42) (xy 110.49 60.96)
		)
		(stroke
			(width 0)
			(type default)
		)
	)
	(wire
		(pts
			(xy 163.83 58.42) (xy 187.96 58.42)
		)
		(stroke
			(width 0)
			(type default)
		)
	)
	(wire
		(pts
			(xy 54.61 50.8) (xy 63.5 50.8)
		)
		(stroke
			(width 0)
			(type default)
		)
	)
	(wire
		(pts
			(xy 142.24 83.82) (xy 158.75 83.82)
		)
		(stroke
			(width 0)
			(type default)
		)
	)
	(wire
		(pts
			(xy 54.61 50.8) (xy 54.61 52.07)
		)
		(stroke
			(width 0)
			(type default)
		)
	)
	(wire
		(pts
			(xy 107.95 104.14) (xy 111.76 104.14)
		)
		(stroke
			(width 0)
			(type default)
		)
	)
	(wire
		(pts
			(xy 45.72 50.8) (xy 54.61 50.8)
		)
		(stroke
			(width 0)
			(type default)
		)
	)
	(wire
		(pts
			(xy 74.93 200.66) (xy 74.93 201.93)
		)
		(stroke
			(width 0)
			(type default)
		)
	)
	(wire
		(pts
			(xy 54.61 81.28) (xy 54.61 102.87)
		)
		(stroke
			(width 0)
			(type default)
		)
	)
	(wire
		(pts
			(xy 97.79 68.58) (xy 97.79 78.74)
		)
		(stroke
			(width 0)
			(type default)
		)
	)
	(wire
		(pts
			(xy 142.24 58.42) (xy 158.75 58.42)
		)
		(stroke
			(width 0)
			(type default)
		)
	)
	(wire
		(pts
			(xy 111.76 60.96) (xy 110.49 60.96)
		)
		(stroke
			(width 0)
			(type default)
		)
	)
	(wire
		(pts
			(xy 110.49 66.04) (xy 110.49 68.58)
		)
		(stroke
			(width 0)
			(type default)
		)
	)
	(polyline
		(pts
			(xy 218.44 134.62) (xy 218.44 284.48)
		)
		(stroke
			(width 0)
			(type dash)
		)
	)
	(bus
		(pts
			(xy 189.23 59.69) (xy 194.31 59.69)
		)
		(stroke
			(width 0)
			(type default)
		)
	)
	(wire
		(pts
			(xy 97.79 78.74) (xy 97.79 93.98)
		)
		(stroke
			(width 0)
			(type default)
		)
	)
	(wire
		(pts
			(xy 142.24 88.9) (xy 158.75 88.9)
		)
		(stroke
			(width 0)
			(type default)
		)
	)
	(wire
		(pts
			(xy 163.83 76.2) (xy 168.91 76.2)
		)
		(stroke
			(width 0)
			(type default)
		)
	)
	(wire
		(pts
			(xy 60.96 83.82) (xy 60.96 102.87)
		)
		(stroke
			(width 0)
			(type default)
		)
	)
	(wire
		(pts
			(xy 142.24 81.28) (xy 158.75 81.28)
		)
		(stroke
			(width 0)
			(type default)
		)
	)
	(wire
		(pts
			(xy 91.44 50.8) (xy 91.44 52.07)
		)
		(stroke
			(width 0)
			(type default)
		)
	)
	(wire
		(pts
			(xy 33.02 81.28) (xy 40.64 81.28)
		)
		(stroke
			(width 0)
			(type default)
		)
	)
	(bus
		(pts
			(xy 189.23 90.17) (xy 194.31 90.17)
		)
		(stroke
			(width 0)
			(type default)
		)
	)
	(wire
		(pts
			(xy 45.72 88.9) (xy 73.66 88.9)
		)
		(stroke
			(width 0)
			(type default)
		)
	)
	(wire
		(pts
			(xy 87.63 97.79) (xy 87.63 99.06)
		)
		(stroke
			(width 0)
			(type default)
		)
	)
	(wire
		(pts
			(xy 91.44 210.82) (xy 91.44 212.09)
		)
		(stroke
			(width 0)
			(type default)
		)
	)
	(bus
		(pts
			(xy 189.23 74.93) (xy 194.31 74.93)
		)
		(stroke
			(width 0)
			(type default)
		)
	)
	(wire
		(pts
			(xy 163.83 60.96) (xy 187.96 60.96)
		)
		(stroke
			(width 0)
			(type default)
		)
	)
	(wire
		(pts
			(xy 81.28 73.66) (xy 111.76 73.66)
		)
		(stroke
			(width 0)
			(type default)
		)
	)
	(wire
		(pts
			(xy 87.63 99.06) (xy 87.63 102.87)
		)
		(stroke
			(width 0)
			(type default)
		)
	)
	(wire
		(pts
			(xy 73.66 88.9) (xy 111.76 88.9)
		)
		(stroke
			(width 0)
			(type default)
		)
	)
	(wire
		(pts
			(xy 142.24 114.3) (xy 143.51 114.3)
		)
		(stroke
			(width 0)
			(type default)
		)
	)
	(wire
		(pts
			(xy 92.71 210.82) (xy 91.44 210.82)
		)
		(stroke
			(width 0)
			(type default)
		)
	)
	(wire
		(pts
			(xy 114.3 187.96) (xy 123.19 187.96)
		)
		(stroke
			(width 0)
			(type default)
		)
	)
	(wire
		(pts
			(xy 124.46 208.28) (xy 123.19 208.28)
		)
		(stroke
			(width 0)
			(type default)
		)
	)
	(wire
		(pts
			(xy 54.61 109.22) (xy 54.61 107.95)
		)
		(stroke
			(width 0)
			(type default)
		)
	)
	(wire
		(pts
			(xy 114.3 187.96) (xy 114.3 189.23)
		)
		(stroke
			(width 0)
			(type default)
		)
	)
	(wire
		(pts
			(xy 168.91 73.66) (xy 171.45 76.2)
		)
		(stroke
			(width 0)
			(type default)
		)
	)
	(wire
		(pts
			(xy 81.28 76.2) (xy 111.76 76.2)
		)
		(stroke
			(width 0)
			(type default)
		)
	)
	(wire
		(pts
			(xy 168.91 66.04) (xy 171.45 68.58)
		)
		(stroke
			(width 0)
			(type default)
		)
	)
	(wire
		(pts
			(xy 100.33 50.8) (xy 100.33 52.07)
		)
		(stroke
			(width 0)
			(type default)
		)
	)
	(wire
		(pts
			(xy 80.01 109.22) (xy 80.01 107.95)
		)
		(stroke
			(width 0)
			(type default)
		)
	)
	(wire
		(pts
			(xy 124.46 210.82) (xy 123.19 210.82)
		)
		(stroke
			(width 0)
			(type default)
		)
	)
	(wire
		(pts
			(xy 123.19 210.82) (xy 123.19 213.36)
		)
		(stroke
			(width 0)
			(type default)
		)
	)
	(wire
		(pts
			(xy 123.19 205.74) (xy 124.46 205.74)
		)
		(stroke
			(width 0)
			(type default)
		)
	)
	(wire
		(pts
			(xy 163.83 81.28) (xy 187.96 81.28)
		)
		(stroke
			(width 0)
			(type default)
		)
	)
	(wire
		(pts
			(xy 114.3 186.69) (xy 114.3 187.96)
		)
		(stroke
			(width 0)
			(type default)
		)
	)
	(wire
		(pts
			(xy 110.49 60.96) (xy 110.49 63.5)
		)
		(stroke
			(width 0)
			(type default)
		)
	)
	(wire
		(pts
			(xy 142.24 91.44) (xy 158.75 91.44)
		)
		(stroke
			(width 0)
			(type default)
		)
	)
	(wire
		(pts
			(xy 87.63 109.22) (xy 87.63 107.95)
		)
		(stroke
			(width 0)
			(type default)
		)
	)
	(wire
		(pts
			(xy 100.33 50.8) (xy 110.49 50.8)
		)
		(stroke
			(width 0)
			(type default)
		)
	)
	(wire
		(pts
			(xy 73.66 102.87) (xy 73.66 88.9)
		)
		(stroke
			(width 0)
			(type default)
		)
	)
	(wire
		(pts
			(xy 187.96 73.66) (xy 171.45 73.66)
		)
		(stroke
			(width 0)
			(type default)
		)
	)
	(wire
		(pts
			(xy 142.24 205.74) (xy 152.4 205.74)
		)
		(stroke
			(width 0)
			(type default)
		)
	)
	(wire
		(pts
			(xy 45.72 91.44) (xy 80.01 91.44)
		)
		(stroke
			(width 0)
			(type default)
		)
	)
	(wire
		(pts
			(xy 124.46 215.9) (xy 123.19 215.9)
		)
		(stroke
			(width 0)
			(type default)
		)
	)
	(wire
		(pts
			(xy 171.45 73.66) (xy 168.91 76.2)
		)
		(stroke
			(width 0)
			(type default)
		)
	)
	(wire
		(pts
			(xy 82.55 50.8) (xy 91.44 50.8)
		)
		(stroke
			(width 0)
			(type default)
		)
	)
	(wire
		(pts
			(xy 63.5 50.8) (xy 73.66 50.8)
		)
		(stroke
			(width 0)
			(type default)
		)
	)
	(polyline
		(pts
			(xy 12.7 134.62) (xy 218.44 134.62)
		)
		(stroke
			(width 0)
			(type dash)
		)
	)
	(wire
		(pts
			(xy 142.24 76.2) (xy 158.75 76.2)
		)
		(stroke
			(width 0)
			(type default)
		)
	)
	(wire
		(pts
			(xy 142.24 111.76) (xy 143.51 111.76)
		)
		(stroke
			(width 0)
			(type default)
		)
	)
	(wire
		(pts
			(xy 142.24 73.66) (xy 158.75 73.66)
		)
		(stroke
			(width 0)
			(type default)
		)
	)
	(wire
		(pts
			(xy 163.83 66.04) (xy 168.91 66.04)
		)
		(stroke
			(width 0)
			(type default)
		)
	)
	(wire
		(pts
			(xy 123.19 213.36) (xy 123.19 215.9)
		)
		(stroke
			(width 0)
			(type default)
		)
	)
	(wire
		(pts
			(xy 171.45 68.58) (xy 187.96 68.58)
		)
		(stroke
			(width 0)
			(type default)
		)
	)
	(wire
		(pts
			(xy 163.83 83.82) (xy 187.96 83.82)
		)
		(stroke
			(width 0)
			(type default)
		)
	)
	(bus
		(pts
			(xy 80.01 74.93) (xy 74.93 74.93)
		)
		(stroke
			(width 0)
			(type default)
		)
	)
	(wire
		(pts
			(xy 73.66 109.22) (xy 73.66 107.95)
		)
		(stroke
			(width 0)
			(type default)
		)
	)
	(wire
		(pts
			(xy 111.76 66.04) (xy 110.49 66.04)
		)
		(stroke
			(width 0)
			(type default)
		)
	)
	(wire
		(pts
			(xy 54.61 81.28) (xy 111.76 81.28)
		)
		(stroke
			(width 0)
			(type default)
		)
	)
	(wire
		(pts
			(xy 80.01 91.44) (xy 111.76 91.44)
		)
		(stroke
			(width 0)
			(type default)
		)
	)
	(wire
		(pts
			(xy 110.49 68.58) (xy 111.76 68.58)
		)
		(stroke
			(width 0)
			(type default)
		)
	)
	(wire
		(pts
			(xy 97.79 96.52) (xy 97.79 93.98)
		)
		(stroke
			(width 0)
			(type default)
		)
	)
	(wire
		(pts
			(xy 85.09 207.01) (xy 85.09 208.28)
		)
		(stroke
			(width 0)
			(type default)
		)
	)
	(wire
		(pts
			(xy 107.95 96.52) (xy 111.76 96.52)
		)
		(stroke
			(width 0)
			(type default)
		)
	)
	(wire
		(pts
			(xy 123.19 187.96) (xy 123.19 203.2)
		)
		(stroke
			(width 0)
			(type default)
		)
	)
	(wire
		(pts
			(xy 91.44 200.66) (xy 91.44 205.74)
		)
		(stroke
			(width 0)
			(type default)
		)
	)
	(wire
		(pts
			(xy 163.83 73.66) (xy 168.91 73.66)
		)
		(stroke
			(width 0)
			(type default)
		)
	)
	(wire
		(pts
			(xy 142.24 60.96) (xy 158.75 60.96)
		)
		(stroke
			(width 0)
			(type default)
		)
	)
	(bus
		(pts
			(xy 189.23 67.31) (xy 194.31 67.31)
		)
		(stroke
			(width 0)
			(type default)
		)
	)
	(wire
		(pts
			(xy 123.19 215.9) (xy 123.19 217.17)
		)
		(stroke
			(width 0)
			(type default)
		)
	)
	(wire
		(pts
			(xy 45.72 86.36) (xy 67.31 86.36)
		)
		(stroke
			(width 0)
			(type default)
		)
	)
	(wire
		(pts
			(xy 67.31 102.87) (xy 67.31 86.36)
		)
		(stroke
			(width 0)
			(type default)
		)
	)
	(wire
		(pts
			(xy 33.02 91.44) (xy 40.64 91.44)
		)
		(stroke
			(width 0)
			(type default)
		)
	)
	(wire
		(pts
			(xy 110.49 50.8) (xy 110.49 58.42)
		)
		(stroke
			(width 0)
			(type default)
		)
	)
	(wire
		(pts
			(xy 142.24 96.52) (xy 151.13 96.52)
		)
		(stroke
			(width 0)
			(type default)
		)
	)
	(wire
		(pts
			(xy 110.49 63.5) (xy 111.76 63.5)
		)
		(stroke
			(width 0)
			(type default)
		)
	)
	(wire
		(pts
			(xy 33.02 86.36) (xy 40.64 86.36)
		)
		(stroke
			(width 0)
			(type default)
		)
	)
	(wire
		(pts
			(xy 74.93 199.39) (xy 74.93 200.66)
		)
		(stroke
			(width 0)
			(type default)
		)
	)
	(wire
		(pts
			(xy 107.95 109.22) (xy 111.76 109.22)
		)
		(stroke
			(width 0)
			(type default)
		)
	)
	(wire
		(pts
			(xy 163.83 88.9) (xy 187.96 88.9)
		)
		(stroke
			(width 0)
			(type default)
		)
	)
	(wire
		(pts
			(xy 45.72 49.53) (xy 45.72 50.8)
		)
		(stroke
			(width 0)
			(type default)
		)
	)
	(wire
		(pts
			(xy 102.87 96.52) (xy 97.79 96.52)
		)
		(stroke
			(width 0)
			(type default)
		)
	)
	(wire
		(pts
			(xy 91.44 50.8) (xy 100.33 50.8)
		)
		(stroke
			(width 0)
			(type default)
		)
	)
	(wire
		(pts
			(xy 142.24 68.58) (xy 158.75 68.58)
		)
		(stroke
			(width 0)
			(type default)
		)
	)
	(wire
		(pts
			(xy 111.76 58.42) (xy 110.49 58.42)
		)
		(stroke
			(width 0)
			(type default)
		)
	)
	(wire
		(pts
			(xy 73.66 50.8) (xy 73.66 52.07)
		)
		(stroke
			(width 0)
			(type default)
		)
	)
	(wire
		(pts
			(xy 142.24 66.04) (xy 158.75 66.04)
		)
		(stroke
			(width 0)
			(type default)
		)
	)
	(bus
		(pts
			(xy 189.23 82.55) (xy 194.31 82.55)
		)
		(stroke
			(width 0)
			(type default)
		)
	)
	(wire
		(pts
			(xy 67.31 86.36) (xy 111.76 86.36)
		)
		(stroke
			(width 0)
			(type default)
		)
	)
	(wire
		(pts
			(xy 187.96 66.04) (xy 171.45 66.04)
		)
		(stroke
			(width 0)
			(type default)
		)
	)
	(wire
		(pts
			(xy 143.51 114.3) (xy 143.51 115.57)
		)
		(stroke
			(width 0)
			(type default)
		)
	)
	(polyline
		(pts
			(xy 218.44 12.7) (xy 218.44 134.62)
		)
		(stroke
			(width 0)
			(type dash)
		)
	)
	(wire
		(pts
			(xy 85.09 200.66) (xy 91.44 200.66)
		)
		(stroke
			(width 0)
			(type default)
		)
	)
	(wire
		(pts
			(xy 111.76 205.74) (xy 123.19 205.74)
		)
		(stroke
			(width 0)
			(type default)
		)
	)
	(wire
		(pts
			(xy 142.24 99.06) (xy 151.13 99.06)
		)
		(stroke
			(width 0)
			(type default)
		)
	)
	(wire
		(pts
			(xy 87.63 92.71) (xy 87.63 78.74)
		)
		(stroke
			(width 0)
			(type default)
		)
	)
	(wire
		(pts
			(xy 123.19 208.28) (xy 123.19 205.74)
		)
		(stroke
			(width 0)
			(type default)
		)
	)
	(wire
		(pts
			(xy 97.79 93.98) (xy 102.87 93.98)
		)
		(stroke
			(width 0)
			(type default)
		)
	)
	(wire
		(pts
			(xy 87.63 78.74) (xy 97.79 78.74)
		)
		(stroke
			(width 0)
			(type default)
		)
	)
	(wire
		(pts
			(xy 163.83 91.44) (xy 187.96 91.44)
		)
		(stroke
			(width 0)
			(type default)
		)
	)
	(wire
		(pts
			(xy 107.95 93.98) (xy 111.76 93.98)
		)
		(stroke
			(width 0)
			(type default)
		)
	)
	(wire
		(pts
			(xy 74.93 200.66) (xy 85.09 200.66)
		)
		(stroke
			(width 0)
			(type default)
		)
	)
	(wire
		(pts
			(xy 67.31 109.22) (xy 67.31 107.95)
		)
		(stroke
			(width 0)
			(type default)
		)
	)
	(wire
		(pts
			(xy 60.96 109.22) (xy 60.96 107.95)
		)
		(stroke
			(width 0)
			(type default)
		)
	)
	(wire
		(pts
			(xy 171.45 76.2) (xy 187.96 76.2)
		)
		(stroke
			(width 0)
			(type default)
		)
	)
	(wire
		(pts
			(xy 124.46 213.36) (xy 123.19 213.36)
		)
		(stroke
			(width 0)
			(type default)
		)
	)
	(wire
		(pts
			(xy 111.76 83.82) (xy 60.96 83.82)
		)
		(stroke
			(width 0)
			(type default)
		)
	)
	(wire
		(pts
			(xy 80.01 102.87) (xy 80.01 91.44)
		)
		(stroke
			(width 0)
			(type default)
		)
	)
	(wire
		(pts
			(xy 91.44 205.74) (xy 92.71 205.74)
		)
		(stroke
			(width 0)
			(type default)
		)
	)
	(wire
		(pts
			(xy 33.02 88.9) (xy 40.64 88.9)
		)
		(stroke
			(width 0)
			(type default)
		)
	)
	(wire
		(pts
			(xy 123.19 203.2) (xy 124.46 203.2)
		)
		(stroke
			(width 0)
			(type default)
		)
	)
	(wire
		(pts
			(xy 143.51 111.76) (xy 143.51 114.3)
		)
		(stroke
			(width 0)
			(type default)
		)
	)
	(wire
		(pts
			(xy 110.49 66.04) (xy 110.49 63.5)
		)
		(stroke
			(width 0)
			(type default)
		)
	)
	(wire
		(pts
			(xy 45.72 50.8) (xy 45.72 52.07)
		)
		(stroke
			(width 0)
			(type default)
		)
	)
	(wire
		(pts
			(xy 85.09 200.66) (xy 85.09 201.93)
		)
		(stroke
			(width 0)
			(type default)
		)
	)
	(wire
		(pts
			(xy 163.83 68.58) (xy 168.91 68.58)
		)
		(stroke
			(width 0)
			(type default)
		)
	)
	(wire
		(pts
			(xy 85.09 208.28) (xy 92.71 208.28)
		)
		(stroke
			(width 0)
			(type default)
		)
	)
	(wire
		(pts
			(xy 45.72 83.82) (xy 60.96 83.82)
		)
		(stroke
			(width 0)
			(type default)
		)
	)
	(wire
		(pts
			(xy 33.02 83.82) (xy 40.64 83.82)
		)
		(stroke
			(width 0)
			(type default)
		)
	)
	(wire
		(pts
			(xy 63.5 50.8) (xy 63.5 52.07)
		)
		(stroke
			(width 0)
			(type default)
		)
	)
	(wire
		(pts
			(xy 107.95 106.68) (xy 111.76 106.68)
		)
		(stroke
			(width 0)
			(type default)
		)
	)
	(wire
		(pts
			(xy 82.55 50.8) (xy 82.55 52.07)
		)
		(stroke
			(width 0)
			(type default)
		)
	)
	(wire
		(pts
			(xy 87.63 99.06) (xy 111.76 99.06)
		)
		(stroke
			(width 0)
			(type default)
		)
	)
	(label "PCIE_{REF1}.CK-"
		(at 173.99 91.44 0)
		(effects
			(font
				(size 1.27 1.27)
			)
			(justify left bottom)
		)
	)
	(label "DIF2+"
		(at 144.78 73.66 0)
		(effects
			(font
				(size 1.27 1.27)
			)
			(justify left bottom)
		)
	)
	(label "PCIE_{REFIN}.CK+"
		(at 81.28 73.66 0)
		(effects
			(font
				(size 1.27 1.27)
			)
			(justify left bottom)
		)
	)
	(label "PCIE_{REF3}.CK+"
		(at 173.99 66.04 0)
		(effects
			(font
				(size 1.27 1.27)
			)
			(justify left bottom)
		)
	)
	(label "PCIE_{REF4}.CK-"
		(at 173.99 83.82 0)
		(effects
			(font
				(size 1.27 1.27)
			)
			(justify left bottom)
		)
	)
	(label "PCIE_{REF1}.CK+"
		(at 173.99 88.9 0)
		(effects
			(font
				(size 1.27 1.27)
			)
			(justify left bottom)
		)
	)
	(label "PCIE_{REF0}.CK-"
		(at 173.99 60.96 0)
		(effects
			(font
				(size 1.27 1.27)
			)
			(justify left bottom)
		)
	)
	(label "DIF3+"
		(at 144.78 81.28 0)
		(effects
			(font
				(size 1.27 1.27)
			)
			(justify left bottom)
		)
	)
	(label "PCIE_{REF2}.CK+"
		(at 173.99 73.66 0)
		(effects
			(font
				(size 1.27 1.27)
			)
			(justify left bottom)
		)
	)
	(label "DIF0+"
		(at 144.78 58.42 0)
		(effects
			(font
				(size 1.27 1.27)
			)
			(justify left bottom)
		)
	)
	(label "DIF2-"
		(at 144.78 76.2 0)
		(effects
			(font
				(size 1.27 1.27)
			)
			(justify left bottom)
		)
	)
	(label "DIF4-"
		(at 144.78 91.44 0)
		(effects
			(font
				(size 1.27 1.27)
			)
			(justify left bottom)
		)
	)
	(label "DIF3-"
		(at 144.78 83.82 0)
		(effects
			(font
				(size 1.27 1.27)
			)
			(justify left bottom)
		)
	)
	(label "DIF0-"
		(at 144.78 60.96 0)
		(effects
			(font
				(size 1.27 1.27)
			)
			(justify left bottom)
		)
	)
	(label "PCIE_{REF2}.CK-"
		(at 173.99 76.2 0)
		(effects
			(font
				(size 1.27 1.27)
			)
			(justify left bottom)
		)
	)
	(label "PCIE_{REF0}.CK+"
		(at 173.99 58.42 0)
		(effects
			(font
				(size 1.27 1.27)
			)
			(justify left bottom)
		)
	)
	(label "DIF5+"
		(at 144.78 96.52 0)
		(effects
			(font
				(size 1.27 1.27)
			)
			(justify left bottom)
		)
	)
	(label "PCIE_{REF3}.CK-"
		(at 173.99 68.58 0)
		(effects
			(font
				(size 1.27 1.27)
			)
			(justify left bottom)
		)
	)
	(label "DIF4+"
		(at 144.78 88.9 0)
		(effects
			(font
				(size 1.27 1.27)
			)
			(justify left bottom)
		)
	)
	(label "DIF5-"
		(at 144.78 99.06 0)
		(effects
			(font
				(size 1.27 1.27)
			)
			(justify left bottom)
		)
	)
	(label "PCIE_{REF4}.CK+"
		(at 173.99 81.28 0)
		(effects
			(font
				(size 1.27 1.27)
			)
			(justify left bottom)
		)
	)
	(label "DIF1+"
		(at 144.78 66.04 0)
		(effects
			(font
				(size 1.27 1.27)
			)
			(justify left bottom)
		)
	)
	(label "DIF1-"
		(at 144.78 68.58 0)
		(effects
			(font
				(size 1.27 1.27)
			)
			(justify left bottom)
		)
	)
	(label "PCIE_{REFIN}.CK-"
		(at 81.28 76.2 0)
		(effects
			(font
				(size 1.27 1.27)
			)
			(justify left bottom)
		)
	)
	(hierarchical_label "PCIE_{REF4}{PCIe_{REF}}"
		(shape output)
		(at 194.31 82.55 0)
		(effects
			(font
				(size 1.27 1.27)
			)
			(justify left)
		)
	)
	(hierarchical_label "PCIE_{REF3}{PCIe_{REF}}"
		(shape output)
		(at 194.31 67.31 0)
		(effects
			(font
				(size 1.27 1.27)
			)
			(justify left)
		)
	)
	(hierarchical_label "~{CLKREQ3}"
		(shape input)
		(at 33.02 83.82 180)
		(effects
			(font
				(size 1.27 1.27)
			)
			(justify right)
		)
	)
	(hierarchical_label "PCIE_{REF2}{PCIe_{REF}}"
		(shape output)
		(at 194.31 74.93 0)
		(effects
			(font
				(size 1.27 1.27)
			)
			(justify left)
		)
	)
	(hierarchical_label "SUSCLK"
		(shape output)
		(at 152.4 205.74 0)
		(effects
			(font
				(size 1.27 1.27)
			)
			(justify left)
		)
	)
	(hierarchical_label "~{CLKREQ4}"
		(shape input)
		(at 33.02 88.9 180)
		(effects
			(font
				(size 1.27 1.27)
			)
			(justify right)
		)
	)
	(hierarchical_label "~{CLKREQ0}"
		(shape input)
		(at 33.02 81.28 180)
		(effects
			(font
				(size 1.27 1.27)
			)
			(justify right)
		)
	)
	(hierarchical_label "~{CLKREQ1}"
		(shape input)
		(at 33.02 91.44 180)
		(effects
			(font
				(size 1.27 1.27)
			)
			(justify right)
		)
	)
	(hierarchical_label "PCIE_{REF0}{PCIe_{REF}}"
		(shape output)
		(at 194.31 59.69 0)
		(effects
			(font
				(size 1.27 1.27)
			)
			(justify left)
		)
	)
	(hierarchical_label "PCIE_{REFIN}{PCIe_{REF}}"
		(shape input)
		(at 74.93 74.93 180)
		(effects
			(font
				(size 1.27 1.27)
			)
			(justify right)
		)
	)
	(hierarchical_label "PCIE_{REF1}{PCIe_{REF}}"
		(shape output)
		(at 194.31 90.17 0)
		(effects
			(font
				(size 1.27 1.27)
			)
			(justify left)
		)
	)
	(hierarchical_label "~{CLKREQ2}"
		(shape input)
		(at 33.02 86.36 180)
		(effects
			(font
				(size 1.27 1.27)
			)
			(justify right)
		)
	)
	(symbol
		(lib_id "antmicropower:GND")
		(at 73.66 57.15 0)
		(unit 1)
		(exclude_from_sim no)
		(in_bom yes)
		(on_board yes)
		(dnp no)
		(property "Reference" "#PWR0265"
			(at 73.66 63.5 0)
			(effects
				(font
					(size 1.27 1.27)
				)
				(justify left bottom)
				(hide yes)
			)
		)
		(property "Value" "GND"
			(at 71.755 62.23 0)
			(effects
				(font
					(size 1.27 1.27)
				)
				(justify left bottom)
			)
		)
		(property "Footprint" ""
			(at 73.66 57.15 0)
			(effects
				(font
					(size 1.27 1.27)
				)
				(justify left bottom)
				(hide yes)
			)
		)
		(property "Datasheet" ""
			(at 73.66 57.15 0)
			(effects
				(font
					(size 1.27 1.27)
				)
				(justify left bottom)
				(hide yes)
			)
		)
		(property "Description" ""
			(at 73.66 57.15 0)
			(effects
				(font
					(size 1.27 1.27)
				)
				(hide yes)
			)
		)
		(property "Author" "Antmicro"
			(at 82.55 64.77 0)
			(effects
				(font
					(size 1.27 1.27)
					(thickness 0.15)
				)
				(justify left bottom)
				(hide yes)
			)
		)
		(property "License" "Apache-2.0"
			(at 82.55 67.31 0)
			(effects
				(font
					(size 1.27 1.27)
					(thickness 0.15)
				)
				(justify left bottom)
				(hide yes)
			)
		)
		(pin "1"
		)
		(instances
			(project "com-express-7-baseboard"
				(path ""
					(reference "#PWR0265")
					(unit 1)
				)
			)
		)
	)
	(symbol
		(lib_id "antmicroResistors0402:R_0R_0402")
		(at 40.64 81.28 0)
		(unit 1)
		(exclude_from_sim no)
		(in_bom yes)
		(on_board yes)
		(dnp yes)
		(property "Reference" "R178"
			(at 38.1 80.01 0)
			(effects
				(font
					(size 1.27 1.27)
					(thickness 0.15)
				)
			)
		)
		(property "Value" "R_0R_0402"
			(at 60.96 93.98 0)
			(effects
				(font
					(size 1.27 1.27)
					(thickness 0.15)
				)
				(justify left bottom)
				(hide yes)
			)
		)
		(property "Footprint" "antmicro-footprints:R_0402_1005Metric"
			(at 60.96 96.52 0)
			(effects
				(font
					(size 1.27 1.27)
					(thickness 0.15)
				)
				(justify left bottom)
				(hide yes)
			)
		)
		(property "Datasheet" "https://industrial.panasonic.com/cdbs/www-data/pdf/RDA0000/AOA0000C301.pdf"
			(at 60.96 99.06 0)
			(effects
				(font
					(size 1.27 1.27)
					(thickness 0.15)
				)
				(justify left bottom)
				(hide yes)
			)
		)
		(property "Description" ""
			(at 40.64 81.28 0)
			(effects
				(font
					(size 1.27 1.27)
				)
				(hide yes)
			)
		)
		(property "MPN" "ERJ2GE0R00X"
			(at 60.96 101.6 0)
			(effects
				(font
					(size 1.27 1.27)
					(thickness 0.15)
				)
				(justify left bottom)
				(hide yes)
			)
		)
		(property "Manufacturer" "Panasonic"
			(at 60.96 104.14 0)
			(effects
				(font
					(size 1.27 1.27)
					(thickness 0.15)
				)
				(justify left bottom)
				(hide yes)
			)
		)
		(property "License" "Apache-2.0"
			(at 60.96 106.68 0)
			(effects
				(font
					(size 1.27 1.27)
					(thickness 0.15)
				)
				(justify left bottom)
				(hide yes)
			)
		)
		(property "Author" "Antmicro"
			(at 60.96 109.22 0)
			(effects
				(font
					(size 1.27 1.27)
					(thickness 0.15)
				)
				(justify left bottom)
				(hide yes)
			)
		)
		(property "Val" "0R"
			(at 46.99 80.01 0)
			(effects
				(font
					(size 1.27 1.27)
					(thickness 0.15)
				)
			)
		)
		(property "Tolerance" "~"
			(at 60.96 91.44 0)
			(effects
				(font
					(size 1.27 1.27)
				)
				(justify left bottom)
				(hide yes)
			)
		)
		(property "Current" "1A"
			(at 60.96 111.76 0)
			(effects
				(font
					(size 1.27 1.27)
					(thickness 0.15)
				)
				(justify left bottom)
				(hide yes)
			)
		)
		(property "Public" "False"
			(at 60.96 111.76 0)
			(effects
				(font
					(size 1.27 1.27)
				)
				(justify left bottom)
				(hide yes)
			)
		)
		(pin "1"
		)
		(pin "2"
		)
		(instances
			(project "com-express-7-baseboard"
				(path ""
					(reference "R178")
					(unit 1)
				)
			)
		)
	)
	(symbol
		(lib_id "antmicroCapacitors0603:C_22u_16V_0603")
		(at 45.72 57.15 90)
		(unit 1)
		(exclude_from_sim no)
		(in_bom yes)
		(on_board yes)
		(dnp no)
		(fields_autoplaced yes)
		(property "Reference" "C106"
			(at 48.26 53.3335 90)
			(effects
				(font
					(size 1.27 1.27)
					(thickness 0.15)
				)
				(justify right)
			)
		)
		(property "Value" "C_22u_16V_0603"
			(at 55.88 36.83 0)
			(effects
				(font
					(size 1.27 1.27)
					(thickness 0.15)
				)
				(justify left bottom)
				(hide yes)
			)
		)
		(property "Footprint" "antmicro-footprints:C_0603_1608Metric"
			(at 58.42 36.83 0)
			(effects
				(font
					(size 1.27 1.27)
					(thickness 0.15)
				)
				(justify left bottom)
				(hide yes)
			)
		)
		(property "Datasheet" "https://product.samsungsem.com/mlcc/CL10A226MO7JZN.do"
			(at 60.96 36.83 0)
			(effects
				(font
					(size 1.27 1.27)
					(thickness 0.15)
				)
				(justify left bottom)
				(hide yes)
			)
		)
		(property "Description" ""
			(at 45.72 57.15 0)
			(effects
				(font
					(size 1.27 1.27)
				)
				(hide yes)
			)
		)
		(property "MPN" "CL10A226MO7JZNC"
			(at 63.5 36.83 0)
			(effects
				(font
					(size 1.27 1.27)
					(thickness 0.15)
				)
				(justify left bottom)
				(hide yes)
			)
		)
		(property "Manufacturer" "Samsung Electro-Mechanics"
			(at 66.04 36.83 0)
			(effects
				(font
					(size 1.27 1.27)
					(thickness 0.15)
				)
				(justify left bottom)
				(hide yes)
			)
		)
		(property "License" "Apache-2.0"
			(at 68.58 36.83 0)
			(effects
				(font
					(size 1.27 1.27)
					(thickness 0.15)
				)
				(justify left bottom)
				(hide yes)
			)
		)
		(property "Author" "Antmicro"
			(at 71.12 36.83 0)
			(effects
				(font
					(size 1.27 1.27)
					(thickness 0.15)
				)
				(justify left bottom)
				(hide yes)
			)
		)
		(property "Val" "22u"
			(at 48.26 55.8735 90)
			(effects
				(font
					(size 1.27 1.27)
					(thickness 0.15)
				)
				(justify right)
			)
		)
		(property "Voltage" "16V"
			(at 73.66 36.83 0)
			(effects
				(font
					(size 1.27 1.27)
				)
				(justify left bottom)
				(hide yes)
			)
		)
		(property "Dielectric" ""
			(at 76.2 36.83 0)
			(effects
				(font
					(size 1.27 1.27)
				)
				(justify left bottom)
				(hide yes)
			)
		)
		(property "Public" "False"
			(at 78.74 36.83 0)
			(effects
				(font
					(size 1.27 1.27)
				)
				(justify left bottom)
				(hide yes)
			)
		)
		(pin "2"
		)
		(pin "1"
		)
		(instances
			(project "com-express-7-baseboard"
				(path ""
					(reference "C106")
					(unit 1)
				)
			)
		)
	)
	(symbol
		(lib_id "antmicroResistors0402:R_0R_0402")
		(at 40.64 86.36 0)
		(unit 1)
		(exclude_from_sim no)
		(in_bom yes)
		(on_board yes)
		(dnp yes)
		(property "Reference" "R315"
			(at 38.1 85.09 0)
			(effects
				(font
					(size 1.27 1.27)
					(thickness 0.15)
				)
			)
		)
		(property "Value" "R_0R_0402"
			(at 60.96 99.06 0)
			(effects
				(font
					(size 1.27 1.27)
					(thickness 0.15)
				)
				(justify left bottom)
				(hide yes)
			)
		)
		(property "Footprint" "antmicro-footprints:R_0402_1005Metric"
			(at 60.96 101.6 0)
			(effects
				(font
					(size 1.27 1.27)
					(thickness 0.15)
				)
				(justify left bottom)
				(hide yes)
			)
		)
		(property "Datasheet" "https://industrial.panasonic.com/cdbs/www-data/pdf/RDA0000/AOA0000C301.pdf"
			(at 60.96 104.14 0)
			(effects
				(font
					(size 1.27 1.27)
					(thickness 0.15)
				)
				(justify left bottom)
				(hide yes)
			)
		)
		(property "Description" ""
			(at 40.64 86.36 0)
			(effects
				(font
					(size 1.27 1.27)
				)
				(hide yes)
			)
		)
		(property "MPN" "ERJ2GE0R00X"
			(at 60.96 106.68 0)
			(effects
				(font
					(size 1.27 1.27)
					(thickness 0.15)
				)
				(justify left bottom)
				(hide yes)
			)
		)
		(property "Manufacturer" "Panasonic"
			(at 60.96 109.22 0)
			(effects
				(font
					(size 1.27 1.27)
					(thickness 0.15)
				)
				(justify left bottom)
				(hide yes)
			)
		)
		(property "License" "Apache-2.0"
			(at 60.96 111.76 0)
			(effects
				(font
					(size 1.27 1.27)
					(thickness 0.15)
				)
				(justify left bottom)
				(hide yes)
			)
		)
		(property "Author" "Antmicro"
			(at 60.96 114.3 0)
			(effects
				(font
					(size 1.27 1.27)
					(thickness 0.15)
				)
				(justify left bottom)
				(hide yes)
			)
		)
		(property "Val" "0R"
			(at 46.99 85.09 0)
			(effects
				(font
					(size 1.27 1.27)
					(thickness 0.15)
				)
			)
		)
		(property "Tolerance" "~"
			(at 60.96 96.52 0)
			(effects
				(font
					(size 1.27 1.27)
				)
				(justify left bottom)
				(hide yes)
			)
		)
		(property "Current" "1A"
			(at 60.96 116.84 0)
			(effects
				(font
					(size 1.27 1.27)
					(thickness 0.15)
				)
				(justify left bottom)
				(hide yes)
			)
		)
		(property "Public" "False"
			(at 60.96 116.84 0)
			(effects
				(font
					(size 1.27 1.27)
				)
				(justify left bottom)
				(hide yes)
			)
		)
		(pin "1"
		)
		(pin "2"
		)
		(instances
			(project "com-express-7-baseboard"
				(path ""
					(reference "R315")
					(unit 1)
				)
			)
		)
	)
	(symbol
		(lib_id "antmicroResistors0402:R_0R_0402")
		(at 158.75 73.66 0)
		(unit 1)
		(exclude_from_sim no)
		(in_bom yes)
		(on_board yes)
		(dnp no)
		(property "Reference" "R196"
			(at 156.21 72.39 0)
			(effects
				(font
					(size 1.27 1.27)
					(thickness 0.15)
				)
			)
		)
		(property "Value" "R_0R_0402"
			(at 179.07 86.36 0)
			(effects
				(font
					(size 1.27 1.27)
					(thickness 0.15)
				)
				(justify left bottom)
				(hide yes)
			)
		)
		(property "Footprint" "antmicro-footprints:R_0402_1005Metric"
			(at 179.07 88.9 0)
			(effects
				(font
					(size 1.27 1.27)
					(thickness 0.15)
				)
				(justify left bottom)
				(hide yes)
			)
		)
		(property "Datasheet" "https://industrial.panasonic.com/cdbs/www-data/pdf/RDA0000/AOA0000C301.pdf"
			(at 179.07 91.44 0)
			(effects
				(font
					(size 1.27 1.27)
					(thickness 0.15)
				)
				(justify left bottom)
				(hide yes)
			)
		)
		(property "Description" ""
			(at 158.75 73.66 0)
			(effects
				(font
					(size 1.27 1.27)
				)
				(hide yes)
			)
		)
		(property "MPN" "ERJ2GE0R00X"
			(at 179.07 93.98 0)
			(effects
				(font
					(size 1.27 1.27)
					(thickness 0.15)
				)
				(justify left bottom)
				(hide yes)
			)
		)
		(property "Manufacturer" "Panasonic"
			(at 179.07 96.52 0)
			(effects
				(font
					(size 1.27 1.27)
					(thickness 0.15)
				)
				(justify left bottom)
				(hide yes)
			)
		)
		(property "License" "Apache-2.0"
			(at 179.07 99.06 0)
			(effects
				(font
					(size 1.27 1.27)
					(thickness 0.15)
				)
				(justify left bottom)
				(hide yes)
			)
		)
		(property "Author" "Antmicro"
			(at 179.07 101.6 0)
			(effects
				(font
					(size 1.27 1.27)
					(thickness 0.15)
				)
				(justify left bottom)
				(hide yes)
			)
		)
		(property "Val" "0R"
			(at 165.1 72.39 0)
			(effects
				(font
					(size 1.27 1.27)
					(thickness 0.15)
				)
			)
		)
		(property "Tolerance" "~"
			(at 179.07 83.82 0)
			(effects
				(font
					(size 1.27 1.27)
				)
				(justify left bottom)
				(hide yes)
			)
		)
		(property "Current" "1A"
			(at 179.07 104.14 0)
			(effects
				(font
					(size 1.27 1.27)
					(thickness 0.15)
				)
				(justify left bottom)
				(hide yes)
			)
		)
		(property "Public" "False"
			(at 179.07 104.14 0)
			(effects
				(font
					(size 1.27 1.27)
				)
				(justify left bottom)
				(hide yes)
			)
		)
		(pin "1"
		)
		(pin "2"
		)
		(instances
			(project "com-express-7-baseboard"
				(path ""
					(reference "R196")
					(unit 1)
				)
			)
		)
	)
	(symbol
		(lib_id "antmicroResistors0402:R_1k_0402")
		(at 107.95 93.98 180)
		(unit 1)
		(exclude_from_sim no)
		(in_bom yes)
		(on_board yes)
		(dnp no)
		(property "Reference" "R189"
			(at 102.87 92.71 0)
			(effects
				(font
					(size 1.27 1.27)
					(thickness 0.15)
				)
				(justify left)
			)
		)
		(property "Value" "R_1k_0402"
			(at 87.63 81.28 0)
			(effects
				(font
					(size 1.27 1.27)
					(thickness 0.15)
				)
				(justify left bottom)
				(hide yes)
			)
		)
		(property "Footprint" "antmicro-footprints:R_0402_1005Metric"
			(at 87.63 78.74 0)
			(effects
				(font
					(size 1.27 1.27)
					(thickness 0.15)
				)
				(justify left bottom)
				(hide yes)
			)
		)
		(property "Datasheet" "https://www.bourns.com/docs/product-datasheets/cr.pdf"
			(at 87.63 76.2 0)
			(effects
				(font
					(size 1.27 1.27)
					(thickness 0.15)
				)
				(justify left bottom)
				(hide yes)
			)
		)
		(property "Description" ""
			(at 107.95 93.98 0)
			(effects
				(font
					(size 1.27 1.27)
				)
				(hide yes)
			)
		)
		(property "MPN" "CR0402-FX-1001GLF"
			(at 87.63 73.66 0)
			(effects
				(font
					(size 1.27 1.27)
					(thickness 0.15)
				)
				(justify left bottom)
				(hide yes)
			)
		)
		(property "Manufacturer" "Bourns"
			(at 87.63 71.12 0)
			(effects
				(font
					(size 1.27 1.27)
					(thickness 0.15)
				)
				(justify left bottom)
				(hide yes)
			)
		)
		(property "License" "Apache-2.0"
			(at 87.63 68.58 0)
			(effects
				(font
					(size 1.27 1.27)
					(thickness 0.15)
				)
				(justify left bottom)
				(hide yes)
			)
		)
		(property "Author" "Antmicro"
			(at 87.63 66.04 0)
			(effects
				(font
					(size 1.27 1.27)
					(thickness 0.15)
				)
				(justify left bottom)
				(hide yes)
			)
		)
		(property "Val" "1k"
			(at 110.49 92.71 0)
			(effects
				(font
					(size 1.27 1.27)
					(thickness 0.15)
				)
				(justify left)
			)
		)
		(property "Tolerance" "1%"
			(at 87.63 83.82 0)
			(effects
				(font
					(size 1.27 1.27)
				)
				(justify left bottom)
				(hide yes)
			)
		)
		(property "Public" "False"
			(at 87.63 63.5 0)
			(effects
				(font
					(size 1.27 1.27)
				)
				(justify left bottom)
				(hide yes)
			)
		)
		(pin "2"
		)
		(pin "1"
		)
		(instances
			(project "com-express-7-baseboard"
				(path ""
					(reference "R189")
					(unit 1)
				)
			)
		)
	)
	(symbol
		(lib_id "antmicropower:+3V3")
		(at 97.79 68.58 0)
		(unit 1)
		(exclude_from_sim no)
		(in_bom yes)
		(on_board yes)
		(dnp no)
		(property "Reference" "#PWR0281"
			(at 113.03 68.58 0)
			(effects
				(font
					(size 1.27 1.27)
					(thickness 0.15)
				)
				(justify left bottom)
				(hide yes)
			)
		)
		(property "Value" "+3V3"
			(at 93.98 67.31 0)
			(effects
				(font
					(size 1.27 1.27)
					(thickness 0.15)
				)
			)
		)
		(property "Footprint" ""
			(at 113.03 76.2 0)
			(effects
				(font
					(size 1.27 1.27)
					(thickness 0.15)
				)
				(justify left bottom)
				(hide yes)
			)
		)
		(property "Datasheet" ""
			(at 113.03 78.74 0)
			(effects
				(font
					(size 1.27 1.27)
					(thickness 0.15)
				)
				(justify left bottom)
				(hide yes)
			)
		)
		(property "Description" ""
			(at 97.79 68.58 0)
			(effects
				(font
					(size 1.27 1.27)
				)
				(hide yes)
			)
		)
		(property "Author" "Antmicro"
			(at 113.03 71.12 0)
			(effects
				(font
					(size 1.27 1.27)
					(thickness 0.15)
				)
				(justify left bottom)
				(hide yes)
			)
		)
		(property "License" "Apache-2.0"
			(at 113.03 73.66 0)
			(effects
				(font
					(size 1.27 1.27)
					(thickness 0.15)
				)
				(justify left bottom)
				(hide yes)
			)
		)
		(pin "1"
		)
		(instances
			(project "com-express-7-baseboard"
				(path ""
					(reference "#PWR0281")
					(unit 1)
				)
			)
		)
	)
	(symbol
		(lib_id "antmicropower:GND")
		(at 60.96 109.22 0)
		(unit 1)
		(exclude_from_sim no)
		(in_bom yes)
		(on_board yes)
		(dnp no)
		(property "Reference" "#PWR0272"
			(at 69.85 111.76 0)
			(effects
				(font
					(size 1.27 1.27)
					(thickness 0.15)
				)
				(justify left bottom)
				(hide yes)
			)
		)
		(property "Value" "GND"
			(at 60.96 113.03 0)
			(effects
				(font
					(size 1.27 1.27)
					(thickness 0.15)
				)
			)
		)
		(property "Footprint" ""
			(at 69.85 116.84 0)
			(effects
				(font
					(size 1.27 1.27)
					(thickness 0.15)
				)
				(justify left bottom)
				(hide yes)
			)
		)
		(property "Datasheet" ""
			(at 69.85 121.92 0)
			(effects
				(font
					(size 1.27 1.27)
					(thickness 0.15)
				)
				(justify left bottom)
				(hide yes)
			)
		)
		(property "Description" ""
			(at 60.96 109.22 0)
			(effects
				(font
					(size 1.27 1.27)
				)
				(hide yes)
			)
		)
		(property "Author" "Antmicro"
			(at 69.85 116.84 0)
			(effects
				(font
					(size 1.27 1.27)
					(thickness 0.15)
				)
				(justify left bottom)
				(hide yes)
			)
		)
		(property "License" "Apache-2.0"
			(at 69.85 119.38 0)
			(effects
				(font
					(size 1.27 1.27)
					(thickness 0.15)
				)
				(justify left bottom)
				(hide yes)
			)
		)
		(pin "1"
		)
		(instances
			(project "com-express-7-baseboard"
				(path ""
					(reference "#PWR0272")
					(unit 1)
				)
			)
		)
	)
	(symbol
		(lib_id "antmicropower:GND")
		(at 73.66 109.22 0)
		(unit 1)
		(exclude_from_sim no)
		(in_bom yes)
		(on_board yes)
		(dnp no)
		(property "Reference" "#PWR0276"
			(at 82.55 111.76 0)
			(effects
				(font
					(size 1.27 1.27)
					(thickness 0.15)
				)
				(justify left bottom)
				(hide yes)
			)
		)
		(property "Value" "GND"
			(at 73.66 113.03 0)
			(effects
				(font
					(size 1.27 1.27)
					(thickness 0.15)
				)
			)
		)
		(property "Footprint" ""
			(at 82.55 116.84 0)
			(effects
				(font
					(size 1.27 1.27)
					(thickness 0.15)
				)
				(justify left bottom)
				(hide yes)
			)
		)
		(property "Datasheet" ""
			(at 82.55 121.92 0)
			(effects
				(font
					(size 1.27 1.27)
					(thickness 0.15)
				)
				(justify left bottom)
				(hide yes)
			)
		)
		(property "Description" ""
			(at 73.66 109.22 0)
			(effects
				(font
					(size 1.27 1.27)
				)
				(hide yes)
			)
		)
		(property "Author" "Antmicro"
			(at 82.55 116.84 0)
			(effects
				(font
					(size 1.27 1.27)
					(thickness 0.15)
				)
				(justify left bottom)
				(hide yes)
			)
		)
		(property "License" "Apache-2.0"
			(at 82.55 119.38 0)
			(effects
				(font
					(size 1.27 1.27)
					(thickness 0.15)
				)
				(justify left bottom)
				(hide yes)
			)
		)
		(pin "1"
		)
		(instances
			(project "com-express-7-baseboard"
				(path ""
					(reference "#PWR0276")
					(unit 1)
				)
			)
		)
	)
	(symbol
		(lib_id "antmicropower:GND")
		(at 63.5 57.15 0)
		(unit 1)
		(exclude_from_sim no)
		(in_bom yes)
		(on_board yes)
		(dnp no)
		(property "Reference" "#PWR0280"
			(at 63.5 63.5 0)
			(effects
				(font
					(size 1.27 1.27)
				)
				(justify left bottom)
				(hide yes)
			)
		)
		(property "Value" "GND"
			(at 61.595 62.23 0)
			(effects
				(font
					(size 1.27 1.27)
				)
				(justify left bottom)
			)
		)
		(property "Footprint" ""
			(at 63.5 57.15 0)
			(effects
				(font
					(size 1.27 1.27)
				)
				(justify left bottom)
				(hide yes)
			)
		)
		(property "Datasheet" ""
			(at 63.5 57.15 0)
			(effects
				(font
					(size 1.27 1.27)
				)
				(justify left bottom)
				(hide yes)
			)
		)
		(property "Description" ""
			(at 63.5 57.15 0)
			(effects
				(font
					(size 1.27 1.27)
				)
				(hide yes)
			)
		)
		(property "Author" "Antmicro"
			(at 72.39 64.77 0)
			(effects
				(font
					(size 1.27 1.27)
					(thickness 0.15)
				)
				(justify left bottom)
				(hide yes)
			)
		)
		(property "License" "Apache-2.0"
			(at 72.39 67.31 0)
			(effects
				(font
					(size 1.27 1.27)
					(thickness 0.15)
				)
				(justify left bottom)
				(hide yes)
			)
		)
		(pin "1"
		)
		(instances
			(project "com-express-7-baseboard"
				(path ""
					(reference "#PWR0280")
					(unit 1)
				)
			)
		)
	)
	(symbol
		(lib_id "antmicroCapacitors0402:C_100n_0402")
		(at 100.33 57.15 90)
		(unit 1)
		(exclude_from_sim no)
		(in_bom yes)
		(on_board yes)
		(dnp no)
		(fields_autoplaced yes)
		(property "Reference" "C104"
			(at 102.87 53.3336 90)
			(effects
				(font
					(size 1.27 1.27)
					(thickness 0.15)
				)
				(justify right)
			)
		)
		(property "Value" "C_100n_0402"
			(at 110.49 36.83 0)
			(effects
				(font
					(size 1.27 1.27)
					(thickness 0.15)
				)
				(justify left bottom)
				(hide yes)
			)
		)
		(property "Footprint" "antmicro-footprints:C_0402_1005Metric"
			(at 113.03 36.83 0)
			(effects
				(font
					(size 1.27 1.27)
					(thickness 0.15)
				)
				(justify left bottom)
				(hide yes)
			)
		)
		(property "Datasheet" "https://www.murata.com/products/productdetail?partno=GRM155R61H104KE14%23"
			(at 115.57 36.83 0)
			(effects
				(font
					(size 1.27 1.27)
					(thickness 0.15)
				)
				(justify left bottom)
				(hide yes)
			)
		)
		(property "Description" ""
			(at 100.33 57.15 0)
			(effects
				(font
					(size 1.27 1.27)
				)
				(hide yes)
			)
		)
		(property "MPN" "GRM155R61H104KE14D"
			(at 118.11 36.83 0)
			(effects
				(font
					(size 1.27 1.27)
					(thickness 0.15)
				)
				(justify left bottom)
				(hide yes)
			)
		)
		(property "Manufacturer" "Murata"
			(at 120.65 36.83 0)
			(effects
				(font
					(size 1.27 1.27)
					(thickness 0.15)
				)
				(justify left bottom)
				(hide yes)
			)
		)
		(property "License" "Apache-2.0"
			(at 123.19 36.83 0)
			(effects
				(font
					(size 1.27 1.27)
					(thickness 0.15)
				)
				(justify left bottom)
				(hide yes)
			)
		)
		(property "Author" "Antmicro"
			(at 125.73 36.83 0)
			(effects
				(font
					(size 1.27 1.27)
					(thickness 0.15)
				)
				(justify left bottom)
				(hide yes)
			)
		)
		(property "Val" "100n"
			(at 102.87 55.8736 90)
			(effects
				(font
					(size 1.27 1.27)
					(thickness 0.15)
				)
				(justify right)
			)
		)
		(property "Voltage" "50V"
			(at 128.27 36.83 0)
			(effects
				(font
					(size 1.27 1.27)
				)
				(justify left bottom)
				(hide yes)
			)
		)
		(property "Dielectric" "X5R"
			(at 130.81 36.83 0)
			(effects
				(font
					(size 1.27 1.27)
				)
				(justify left bottom)
				(hide yes)
			)
		)
		(property "Public" "False"
			(at 133.35 36.83 0)
			(effects
				(font
					(size 1.27 1.27)
				)
				(justify left bottom)
				(hide yes)
			)
		)
		(pin "1"
		)
		(pin "2"
		)
		(instances
			(project "com-express-7-baseboard"
				(path ""
					(reference "C104")
					(unit 1)
				)
			)
		)
	)
	(symbol
		(lib_id "antmicroResistors0402:R_1k_0402")
		(at 85.09 207.01 90)
		(unit 1)
		(exclude_from_sim no)
		(in_bom yes)
		(on_board yes)
		(dnp no)
		(property "Reference" "R191"
			(at 86.36 203.2 90)
			(effects
				(font
					(size 1.27 1.27)
					(thickness 0.15)
				)
				(justify right)
			)
		)
		(property "Value" "R_1k_0402"
			(at 97.79 186.69 0)
			(effects
				(font
					(size 1.27 1.27)
					(thickness 0.15)
				)
				(justify left bottom)
				(hide yes)
			)
		)
		(property "Footprint" "antmicro-footprints:R_0402_1005Metric"
			(at 100.33 186.69 0)
			(effects
				(font
					(size 1.27 1.27)
					(thickness 0.15)
				)
				(justify left bottom)
				(hide yes)
			)
		)
		(property "Datasheet" "https://www.bourns.com/docs/product-datasheets/cr.pdf"
			(at 102.87 186.69 0)
			(effects
				(font
					(size 1.27 1.27)
					(thickness 0.15)
				)
				(justify left bottom)
				(hide yes)
			)
		)
		(property "Description" ""
			(at 85.09 207.01 0)
			(effects
				(font
					(size 1.27 1.27)
				)
				(hide yes)
			)
		)
		(property "MPN" "CR0402-FX-1001GLF"
			(at 105.41 186.69 0)
			(effects
				(font
					(size 1.27 1.27)
					(thickness 0.15)
				)
				(justify left bottom)
				(hide yes)
			)
		)
		(property "Manufacturer" "Bourns"
			(at 107.95 186.69 0)
			(effects
				(font
					(size 1.27 1.27)
					(thickness 0.15)
				)
				(justify left bottom)
				(hide yes)
			)
		)
		(property "License" "Apache-2.0"
			(at 110.49 186.69 0)
			(effects
				(font
					(size 1.27 1.27)
					(thickness 0.15)
				)
				(justify left bottom)
				(hide yes)
			)
		)
		(property "Author" "Antmicro"
			(at 113.03 186.69 0)
			(effects
				(font
					(size 1.27 1.27)
					(thickness 0.15)
				)
				(justify left bottom)
				(hide yes)
			)
		)
		(property "Val" "1k"
			(at 86.36 205.74 90)
			(effects
				(font
					(size 1.27 1.27)
					(thickness 0.15)
				)
				(justify right)
			)
		)
		(property "Tolerance" "1%"
			(at 95.25 186.69 0)
			(effects
				(font
					(size 1.27 1.27)
				)
				(justify left bottom)
				(hide yes)
			)
		)
		(property "Public" "False"
			(at 115.57 186.69 0)
			(effects
				(font
					(size 1.27 1.27)
				)
				(justify left bottom)
				(hide yes)
			)
		)
		(pin "2"
		)
		(pin "1"
		)
		(instances
			(project "com-express-7-baseboard"
				(path ""
					(reference "R191")
					(unit 1)
				)
			)
		)
	)
	(symbol
		(lib_id "antmicroResistors0402:R_1k_0402")
		(at 87.63 92.71 90)
		(mirror x)
		(unit 1)
		(exclude_from_sim no)
		(in_bom yes)
		(on_board yes)
		(dnp no)
		(fields_autoplaced yes)
		(property "Reference" "R187"
			(at 90.17 92.71 90)
			(effects
				(font
					(size 1.27 1.27)
					(thickness 0.15)
				)
				(justify right)
			)
		)
		(property "Value" "R_1k_0402"
			(at 100.33 113.03 0)
			(effects
				(font
					(size 1.27 1.27)
					(thickness 0.15)
				)
				(justify left bottom)
				(hide yes)
			)
		)
		(property "Footprint" "antmicro-footprints:R_0402_1005Metric"
			(at 102.87 113.03 0)
			(effects
				(font
					(size 1.27 1.27)
					(thickness 0.15)
				)
				(justify left bottom)
				(hide yes)
			)
		)
		(property "Datasheet" "https://www.bourns.com/docs/product-datasheets/cr.pdf"
			(at 105.41 113.03 0)
			(effects
				(font
					(size 1.27 1.27)
					(thickness 0.15)
				)
				(justify left bottom)
				(hide yes)
			)
		)
		(property "Description" ""
			(at 87.63 92.71 0)
			(effects
				(font
					(size 1.27 1.27)
				)
				(hide yes)
			)
		)
		(property "MPN" "CR0402-FX-1001GLF"
			(at 107.95 113.03 0)
			(effects
				(font
					(size 1.27 1.27)
					(thickness 0.15)
				)
				(justify left bottom)
				(hide yes)
			)
		)
		(property "Manufacturer" "Bourns"
			(at 110.49 113.03 0)
			(effects
				(font
					(size 1.27 1.27)
					(thickness 0.15)
				)
				(justify left bottom)
				(hide yes)
			)
		)
		(property "License" "Apache-2.0"
			(at 113.03 113.03 0)
			(effects
				(font
					(size 1.27 1.27)
					(thickness 0.15)
				)
				(justify left bottom)
				(hide yes)
			)
		)
		(property "Author" "Antmicro"
			(at 115.57 113.03 0)
			(effects
				(font
					(size 1.27 1.27)
					(thickness 0.15)
				)
				(justify left bottom)
				(hide yes)
			)
		)
		(property "Val" "1k"
			(at 90.17 95.25 90)
			(effects
				(font
					(size 1.27 1.27)
					(thickness 0.15)
				)
				(justify right)
			)
		)
		(property "Tolerance" "1%"
			(at 97.79 113.03 0)
			(effects
				(font
					(size 1.27 1.27)
				)
				(justify left bottom)
				(hide yes)
			)
		)
		(property "Public" "False"
			(at 118.11 113.03 0)
			(effects
				(font
					(size 1.27 1.27)
				)
				(justify left bottom)
				(hide yes)
			)
		)
		(pin "2"
		)
		(pin "1"
		)
		(instances
			(project "com-express-7-baseboard"
				(path ""
					(reference "R187")
					(unit 1)
				)
			)
		)
	)
	(symbol
		(lib_id "antmicroResistors0402:R_0R_0402")
		(at 40.64 91.44 0)
		(unit 1)
		(exclude_from_sim no)
		(in_bom yes)
		(on_board yes)
		(dnp yes)
		(property "Reference" "R317"
			(at 38.1 90.17 0)
			(effects
				(font
					(size 1.27 1.27)
					(thickness 0.15)
				)
			)
		)
		(property "Value" "R_0R_0402"
			(at 60.96 104.14 0)
			(effects
				(font
					(size 1.27 1.27)
					(thickness 0.15)
				)
				(justify left bottom)
				(hide yes)
			)
		)
		(property "Footprint" "antmicro-footprints:R_0402_1005Metric"
			(at 60.96 106.68 0)
			(effects
				(font
					(size 1.27 1.27)
					(thickness 0.15)
				)
				(justify left bottom)
				(hide yes)
			)
		)
		(property "Datasheet" "https://industrial.panasonic.com/cdbs/www-data/pdf/RDA0000/AOA0000C301.pdf"
			(at 60.96 109.22 0)
			(effects
				(font
					(size 1.27 1.27)
					(thickness 0.15)
				)
				(justify left bottom)
				(hide yes)
			)
		)
		(property "Description" ""
			(at 40.64 91.44 0)
			(effects
				(font
					(size 1.27 1.27)
				)
				(hide yes)
			)
		)
		(property "MPN" "ERJ2GE0R00X"
			(at 60.96 111.76 0)
			(effects
				(font
					(size 1.27 1.27)
					(thickness 0.15)
				)
				(justify left bottom)
				(hide yes)
			)
		)
		(property "Manufacturer" "Panasonic"
			(at 60.96 114.3 0)
			(effects
				(font
					(size 1.27 1.27)
					(thickness 0.15)
				)
				(justify left bottom)
				(hide yes)
			)
		)
		(property "License" "Apache-2.0"
			(at 60.96 116.84 0)
			(effects
				(font
					(size 1.27 1.27)
					(thickness 0.15)
				)
				(justify left bottom)
				(hide yes)
			)
		)
		(property "Author" "Antmicro"
			(at 60.96 119.38 0)
			(effects
				(font
					(size 1.27 1.27)
					(thickness 0.15)
				)
				(justify left bottom)
				(hide yes)
			)
		)
		(property "Val" "0R"
			(at 46.99 90.17 0)
			(effects
				(font
					(size 1.27 1.27)
					(thickness 0.15)
				)
			)
		)
		(property "Tolerance" "~"
			(at 60.96 101.6 0)
			(effects
				(font
					(size 1.27 1.27)
				)
				(justify left bottom)
				(hide yes)
			)
		)
		(property "Current" "1A"
			(at 60.96 121.92 0)
			(effects
				(font
					(size 1.27 1.27)
					(thickness 0.15)
				)
				(justify left bottom)
				(hide yes)
			)
		)
		(property "Public" "False"
			(at 60.96 121.92 0)
			(effects
				(font
					(size 1.27 1.27)
				)
				(justify left bottom)
				(hide yes)
			)
		)
		(pin "1"
		)
		(pin "2"
		)
		(instances
			(project "com-express-7-baseboard"
				(path ""
					(reference "R317")
					(unit 1)
				)
			)
		)
	)
	(symbol
		(lib_id "antmicropower:+3V3")
		(at 45.72 49.53 0)
		(unit 1)
		(exclude_from_sim no)
		(in_bom yes)
		(on_board yes)
		(dnp no)
		(property "Reference" "#PWR0274"
			(at 60.96 49.53 0)
			(effects
				(font
					(size 1.27 1.27)
					(thickness 0.15)
				)
				(justify left bottom)
				(hide yes)
			)
		)
		(property "Value" "+3V3"
			(at 45.72 45.72 0)
			(effects
				(font
					(size 1.27 1.27)
					(thickness 0.15)
				)
			)
		)
		(property "Footprint" ""
			(at 60.96 57.15 0)
			(effects
				(font
					(size 1.27 1.27)
					(thickness 0.15)
				)
				(justify left bottom)
				(hide yes)
			)
		)
		(property "Datasheet" ""
			(at 60.96 59.69 0)
			(effects
				(font
					(size 1.27 1.27)
					(thickness 0.15)
				)
				(justify left bottom)
				(hide yes)
			)
		)
		(property "Description" ""
			(at 45.72 49.53 0)
			(effects
				(font
					(size 1.27 1.27)
				)
				(hide yes)
			)
		)
		(property "Author" "Antmicro"
			(at 60.96 52.07 0)
			(effects
				(font
					(size 1.27 1.27)
					(thickness 0.15)
				)
				(justify left bottom)
				(hide yes)
			)
		)
		(property "License" "Apache-2.0"
			(at 60.96 54.61 0)
			(effects
				(font
					(size 1.27 1.27)
					(thickness 0.15)
				)
				(justify left bottom)
				(hide yes)
			)
		)
		(pin "1"
		)
		(instances
			(project "com-express-7-baseboard"
				(path ""
					(reference "#PWR0274")
					(unit 1)
				)
			)
		)
	)
	(symbol
		(lib_id "antmicropower:GND")
		(at 54.61 57.15 0)
		(unit 1)
		(exclude_from_sim no)
		(in_bom yes)
		(on_board yes)
		(dnp no)
		(property "Reference" "#PWR0278"
			(at 54.61 63.5 0)
			(effects
				(font
					(size 1.27 1.27)
				)
				(justify left bottom)
				(hide yes)
			)
		)
		(property "Value" "GND"
			(at 52.705 62.23 0)
			(effects
				(font
					(size 1.27 1.27)
				)
				(justify left bottom)
			)
		)
		(property "Footprint" ""
			(at 54.61 57.15 0)
			(effects
				(font
					(size 1.27 1.27)
				)
				(justify left bottom)
				(hide yes)
			)
		)
		(property "Datasheet" ""
			(at 54.61 57.15 0)
			(effects
				(font
					(size 1.27 1.27)
				)
				(justify left bottom)
				(hide yes)
			)
		)
		(property "Description" ""
			(at 54.61 57.15 0)
			(effects
				(font
					(size 1.27 1.27)
				)
				(hide yes)
			)
		)
		(property "Author" "Antmicro"
			(at 63.5 64.77 0)
			(effects
				(font
					(size 1.27 1.27)
					(thickness 0.15)
				)
				(justify left bottom)
				(hide yes)
			)
		)
		(property "License" "Apache-2.0"
			(at 63.5 67.31 0)
			(effects
				(font
					(size 1.27 1.27)
					(thickness 0.15)
				)
				(justify left bottom)
				(hide yes)
			)
		)
		(pin "1"
		)
		(instances
			(project "com-express-7-baseboard"
				(path ""
					(reference "#PWR0278")
					(unit 1)
				)
			)
		)
	)
	(symbol
		(lib_id "antmicroResistors0402:R_0R_0402")
		(at 158.75 68.58 0)
		(unit 1)
		(exclude_from_sim no)
		(in_bom yes)
		(on_board yes)
		(dnp no)
		(property "Reference" "R195"
			(at 156.21 67.31 0)
			(effects
				(font
					(size 1.27 1.27)
					(thickness 0.15)
				)
			)
		)
		(property "Value" "R_0R_0402"
			(at 179.07 81.28 0)
			(effects
				(font
					(size 1.27 1.27)
					(thickness 0.15)
				)
				(justify left bottom)
				(hide yes)
			)
		)
		(property "Footprint" "antmicro-footprints:R_0402_1005Metric"
			(at 179.07 83.82 0)
			(effects
				(font
					(size 1.27 1.27)
					(thickness 0.15)
				)
				(justify left bottom)
				(hide yes)
			)
		)
		(property "Datasheet" "https://industrial.panasonic.com/cdbs/www-data/pdf/RDA0000/AOA0000C301.pdf"
			(at 179.07 86.36 0)
			(effects
				(font
					(size 1.27 1.27)
					(thickness 0.15)
				)
				(justify left bottom)
				(hide yes)
			)
		)
		(property "Description" ""
			(at 158.75 68.58 0)
			(effects
				(font
					(size 1.27 1.27)
				)
				(hide yes)
			)
		)
		(property "MPN" "ERJ2GE0R00X"
			(at 179.07 88.9 0)
			(effects
				(font
					(size 1.27 1.27)
					(thickness 0.15)
				)
				(justify left bottom)
				(hide yes)
			)
		)
		(property "Manufacturer" "Panasonic"
			(at 179.07 91.44 0)
			(effects
				(font
					(size 1.27 1.27)
					(thickness 0.15)
				)
				(justify left bottom)
				(hide yes)
			)
		)
		(property "License" "Apache-2.0"
			(at 179.07 93.98 0)
			(effects
				(font
					(size 1.27 1.27)
					(thickness 0.15)
				)
				(justify left bottom)
				(hide yes)
			)
		)
		(property "Author" "Antmicro"
			(at 179.07 96.52 0)
			(effects
				(font
					(size 1.27 1.27)
					(thickness 0.15)
				)
				(justify left bottom)
				(hide yes)
			)
		)
		(property "Val" "0R"
			(at 165.1 67.31 0)
			(effects
				(font
					(size 1.27 1.27)
					(thickness 0.15)
				)
			)
		)
		(property "Tolerance" "~"
			(at 179.07 78.74 0)
			(effects
				(font
					(size 1.27 1.27)
				)
				(justify left bottom)
				(hide yes)
			)
		)
		(property "Current" "1A"
			(at 179.07 99.06 0)
			(effects
				(font
					(size 1.27 1.27)
					(thickness 0.15)
				)
				(justify left bottom)
				(hide yes)
			)
		)
		(property "Public" "False"
			(at 179.07 99.06 0)
			(effects
				(font
					(size 1.27 1.27)
				)
				(justify left bottom)
				(hide yes)
			)
		)
		(pin "1"
		)
		(pin "2"
		)
		(instances
			(project "com-express-7-baseboard"
				(path ""
					(reference "R195")
					(unit 1)
				)
			)
		)
	)
	(symbol
		(lib_id "antmicroTestPoints:TP_0.75mm_SMD")
		(at 151.13 96.52 0)
		(mirror x)
		(unit 1)
		(exclude_from_sim no)
		(in_bom no)
		(on_board yes)
		(dnp no)
		(property "Reference" "TP47"
			(at 157.48 96.52 0)
			(effects
				(font
					(size 1.27 1.27)
					(thickness 0.15)
				)
			)
		)
		(property "Value" "TP_0.75mm_SMD"
			(at 161.925 92.71 0)
			(effects
				(font
					(size 1.27 1.27)
					(thickness 0.15)
				)
				(justify left bottom)
				(hide yes)
			)
		)
		(property "Footprint" "antmicro-footprints:TP_SMD_0.75mm"
			(at 161.925 90.17 0)
			(effects
				(font
					(size 1.27 1.27)
					(thickness 0.15)
				)
				(justify left bottom)
				(hide yes)
			)
		)
		(property "Datasheet" ""
			(at 168.91 83.82 0)
			(effects
				(font
					(size 1.27 1.27)
					(thickness 0.15)
				)
				(justify left bottom)
				(hide yes)
			)
		)
		(property "Description" ""
			(at 151.13 96.52 0)
			(effects
				(font
					(size 1.27 1.27)
				)
				(hide yes)
			)
		)
		(property "MPN" ""
			(at 161.925 85.09 0)
			(effects
				(font
					(size 1.27 1.27)
					(thickness 0.15)
				)
				(justify left bottom)
				(hide yes)
			)
		)
		(property "Manufacturer" ""
			(at 161.925 90.17 0)
			(effects
				(font
					(size 1.27 1.27)
					(thickness 0.15)
				)
				(justify left bottom)
				(hide yes)
			)
		)
		(property "Author" "Antmicro"
			(at 161.925 87.63 0)
			(effects
				(font
					(size 1.27 1.27)
					(thickness 0.15)
				)
				(justify left bottom)
				(hide yes)
			)
		)
		(property "License" "Apache-2.0"
			(at 161.925 85.09 0)
			(effects
				(font
					(size 1.27 1.27)
					(thickness 0.15)
				)
				(justify left bottom)
				(hide yes)
			)
		)
		(property "Public" "False"
			(at 161.29 82.55 0)
			(effects
				(font
					(size 1.27 1.27)
				)
				(justify left bottom)
				(hide yes)
			)
		)
		(pin "1"
		)
		(instances
			(project "com-express-7-baseboard"
				(path ""
					(reference "TP47")
					(unit 1)
				)
			)
		)
	)
	(symbol
		(lib_id "antmicroResistors0402:R_1k_0402")
		(at 54.61 102.87 270)
		(unit 1)
		(exclude_from_sim no)
		(in_bom yes)
		(on_board yes)
		(dnp no)
		(property "Reference" "R182"
			(at 53.34 102.87 90)
			(effects
				(font
					(size 1.27 1.27)
					(thickness 0.15)
				)
				(justify right)
			)
		)
		(property "Value" "R_1k_0402"
			(at 41.91 123.19 0)
			(effects
				(font
					(size 1.27 1.27)
					(thickness 0.15)
				)
				(justify left bottom)
				(hide yes)
			)
		)
		(property "Footprint" "antmicro-footprints:R_0402_1005Metric"
			(at 39.37 123.19 0)
			(effects
				(font
					(size 1.27 1.27)
					(thickness 0.15)
				)
				(justify left bottom)
				(hide yes)
			)
		)
		(property "Datasheet" "https://www.bourns.com/docs/product-datasheets/cr.pdf"
			(at 36.83 123.19 0)
			(effects
				(font
					(size 1.27 1.27)
					(thickness 0.15)
				)
				(justify left bottom)
				(hide yes)
			)
		)
		(property "Description" ""
			(at 54.61 102.87 0)
			(effects
				(font
					(size 1.27 1.27)
				)
				(hide yes)
			)
		)
		(property "MPN" "CR0402-FX-1001GLF"
			(at 34.29 123.19 0)
			(effects
				(font
					(size 1.27 1.27)
					(thickness 0.15)
				)
				(justify left bottom)
				(hide yes)
			)
		)
		(property "Manufacturer" "Bourns"
			(at 31.75 123.19 0)
			(effects
				(font
					(size 1.27 1.27)
					(thickness 0.15)
				)
				(justify left bottom)
				(hide yes)
			)
		)
		(property "License" "Apache-2.0"
			(at 29.21 123.19 0)
			(effects
				(font
					(size 1.27 1.27)
					(thickness 0.15)
				)
				(justify left bottom)
				(hide yes)
			)
		)
		(property "Author" "Antmicro"
			(at 26.67 123.19 0)
			(effects
				(font
					(size 1.27 1.27)
					(thickness 0.15)
				)
				(justify left bottom)
				(hide yes)
			)
		)
		(property "Val" "1k"
			(at 53.34 105.41 90)
			(effects
				(font
					(size 1.27 1.27)
					(thickness 0.15)
				)
				(justify right)
			)
		)
		(property "Tolerance" "1%"
			(at 44.45 123.19 0)
			(effects
				(font
					(size 1.27 1.27)
				)
				(justify left bottom)
				(hide yes)
			)
		)
		(property "Public" "False"
			(at 24.13 123.19 0)
			(effects
				(font
					(size 1.27 1.27)
				)
				(justify left bottom)
				(hide yes)
			)
		)
		(pin "2"
		)
		(pin "1"
		)
		(instances
			(project "com-express-7-baseboard"
				(path ""
					(reference "R182")
					(unit 1)
				)
			)
		)
	)
	(symbol
		(lib_id "antmicropower:GND")
		(at 114.3 194.31 0)
		(unit 1)
		(exclude_from_sim no)
		(in_bom yes)
		(on_board yes)
		(dnp no)
		(property "Reference" "#PWR0286"
			(at 123.19 196.85 0)
			(effects
				(font
					(size 1.27 1.27)
					(thickness 0.15)
				)
				(justify left bottom)
				(hide yes)
			)
		)
		(property "Value" "GND"
			(at 114.3 198.12 0)
			(effects
				(font
					(size 1.27 1.27)
					(thickness 0.15)
				)
			)
		)
		(property "Footprint" ""
			(at 123.19 201.93 0)
			(effects
				(font
					(size 1.27 1.27)
					(thickness 0.15)
				)
				(justify left bottom)
				(hide yes)
			)
		)
		(property "Datasheet" ""
			(at 123.19 207.01 0)
			(effects
				(font
					(size 1.27 1.27)
					(thickness 0.15)
				)
				(justify left bottom)
				(hide yes)
			)
		)
		(property "Description" ""
			(at 114.3 194.31 0)
			(effects
				(font
					(size 1.27 1.27)
				)
				(hide yes)
			)
		)
		(property "Author" "Antmicro"
			(at 123.19 201.93 0)
			(effects
				(font
					(size 1.27 1.27)
					(thickness 0.15)
				)
				(justify left bottom)
				(hide yes)
			)
		)
		(property "License" "Apache-2.0"
			(at 123.19 204.47 0)
			(effects
				(font
					(size 1.27 1.27)
					(thickness 0.15)
				)
				(justify left bottom)
				(hide yes)
			)
		)
		(pin "1"
		)
		(instances
			(project "com-express-7-baseboard"
				(path ""
					(reference "#PWR0286")
					(unit 1)
				)
			)
		)
	)
	(symbol
		(lib_id "antmicroResistors0402:R_1k_0402")
		(at 73.66 102.87 270)
		(unit 1)
		(exclude_from_sim no)
		(in_bom yes)
		(on_board yes)
		(dnp no)
		(property "Reference" "R185"
			(at 72.39 102.87 90)
			(effects
				(font
					(size 1.27 1.27)
					(thickness 0.15)
				)
				(justify right)
			)
		)
		(property "Value" "R_1k_0402"
			(at 60.96 123.19 0)
			(effects
				(font
					(size 1.27 1.27)
					(thickness 0.15)
				)
				(justify left bottom)
				(hide yes)
			)
		)
		(property "Footprint" "antmicro-footprints:R_0402_1005Metric"
			(at 58.42 123.19 0)
			(effects
				(font
					(size 1.27 1.27)
					(thickness 0.15)
				)
				(justify left bottom)
				(hide yes)
			)
		)
		(property "Datasheet" "https://www.bourns.com/docs/product-datasheets/cr.pdf"
			(at 55.88 123.19 0)
			(effects
				(font
					(size 1.27 1.27)
					(thickness 0.15)
				)
				(justify left bottom)
				(hide yes)
			)
		)
		(property "Description" ""
			(at 73.66 102.87 0)
			(effects
				(font
					(size 1.27 1.27)
				)
				(hide yes)
			)
		)
		(property "MPN" "CR0402-FX-1001GLF"
			(at 53.34 123.19 0)
			(effects
				(font
					(size 1.27 1.27)
					(thickness 0.15)
				)
				(justify left bottom)
				(hide yes)
			)
		)
		(property "Manufacturer" "Bourns"
			(at 50.8 123.19 0)
			(effects
				(font
					(size 1.27 1.27)
					(thickness 0.15)
				)
				(justify left bottom)
				(hide yes)
			)
		)
		(property "License" "Apache-2.0"
			(at 48.26 123.19 0)
			(effects
				(font
					(size 1.27 1.27)
					(thickness 0.15)
				)
				(justify left bottom)
				(hide yes)
			)
		)
		(property "Author" "Antmicro"
			(at 45.72 123.19 0)
			(effects
				(font
					(size 1.27 1.27)
					(thickness 0.15)
				)
				(justify left bottom)
				(hide yes)
			)
		)
		(property "Val" "1k"
			(at 72.39 105.41 90)
			(effects
				(font
					(size 1.27 1.27)
					(thickness 0.15)
				)
				(justify right)
			)
		)
		(property "Tolerance" "1%"
			(at 63.5 123.19 0)
			(effects
				(font
					(size 1.27 1.27)
				)
				(justify left bottom)
				(hide yes)
			)
		)
		(property "Public" "False"
			(at 43.18 123.19 0)
			(effects
				(font
					(size 1.27 1.27)
				)
				(justify left bottom)
				(hide yes)
			)
		)
		(pin "2"
		)
		(pin "1"
		)
		(instances
			(project "com-express-7-baseboard"
				(path ""
					(reference "R185")
					(unit 1)
				)
			)
		)
	)
	(symbol
		(lib_id "antmicroResistors0402:R_0R_0402")
		(at 40.64 83.82 0)
		(unit 1)
		(exclude_from_sim no)
		(in_bom yes)
		(on_board yes)
		(dnp yes)
		(property "Reference" "R314"
			(at 38.1 82.55 0)
			(effects
				(font
					(size 1.27 1.27)
					(thickness 0.15)
				)
			)
		)
		(property "Value" "R_0R_0402"
			(at 60.96 96.52 0)
			(effects
				(font
					(size 1.27 1.27)
					(thickness 0.15)
				)
				(justify left bottom)
				(hide yes)
			)
		)
		(property "Footprint" "antmicro-footprints:R_0402_1005Metric"
			(at 60.96 99.06 0)
			(effects
				(font
					(size 1.27 1.27)
					(thickness 0.15)
				)
				(justify left bottom)
				(hide yes)
			)
		)
		(property "Datasheet" "https://industrial.panasonic.com/cdbs/www-data/pdf/RDA0000/AOA0000C301.pdf"
			(at 60.96 101.6 0)
			(effects
				(font
					(size 1.27 1.27)
					(thickness 0.15)
				)
				(justify left bottom)
				(hide yes)
			)
		)
		(property "Description" ""
			(at 40.64 83.82 0)
			(effects
				(font
					(size 1.27 1.27)
				)
				(hide yes)
			)
		)
		(property "MPN" "ERJ2GE0R00X"
			(at 60.96 104.14 0)
			(effects
				(font
					(size 1.27 1.27)
					(thickness 0.15)
				)
				(justify left bottom)
				(hide yes)
			)
		)
		(property "Manufacturer" "Panasonic"
			(at 60.96 106.68 0)
			(effects
				(font
					(size 1.27 1.27)
					(thickness 0.15)
				)
				(justify left bottom)
				(hide yes)
			)
		)
		(property "License" "Apache-2.0"
			(at 60.96 109.22 0)
			(effects
				(font
					(size 1.27 1.27)
					(thickness 0.15)
				)
				(justify left bottom)
				(hide yes)
			)
		)
		(property "Author" "Antmicro"
			(at 60.96 111.76 0)
			(effects
				(font
					(size 1.27 1.27)
					(thickness 0.15)
				)
				(justify left bottom)
				(hide yes)
			)
		)
		(property "Val" "0R"
			(at 46.99 82.55 0)
			(effects
				(font
					(size 1.27 1.27)
					(thickness 0.15)
				)
			)
		)
		(property "Tolerance" "~"
			(at 60.96 93.98 0)
			(effects
				(font
					(size 1.27 1.27)
				)
				(justify left bottom)
				(hide yes)
			)
		)
		(property "Current" "1A"
			(at 60.96 114.3 0)
			(effects
				(font
					(size 1.27 1.27)
					(thickness 0.15)
				)
				(justify left bottom)
				(hide yes)
			)
		)
		(property "Public" "False"
			(at 60.96 114.3 0)
			(effects
				(font
					(size 1.27 1.27)
				)
				(justify left bottom)
				(hide yes)
			)
		)
		(pin "1"
		)
		(pin "2"
		)
		(instances
			(project "com-express-7-baseboard"
				(path ""
					(reference "R314")
					(unit 1)
				)
			)
		)
	)
	(symbol
		(lib_id "antmicropower:GND")
		(at 74.93 207.01 0)
		(unit 1)
		(exclude_from_sim no)
		(in_bom yes)
		(on_board yes)
		(dnp no)
		(property "Reference" "#PWR0283"
			(at 83.82 209.55 0)
			(effects
				(font
					(size 1.27 1.27)
					(thickness 0.15)
				)
				(justify left bottom)
				(hide yes)
			)
		)
		(property "Value" "GND"
			(at 74.93 210.82 0)
			(effects
				(font
					(size 1.27 1.27)
					(thickness 0.15)
				)
			)
		)
		(property "Footprint" ""
			(at 83.82 214.63 0)
			(effects
				(font
					(size 1.27 1.27)
					(thickness 0.15)
				)
				(justify left bottom)
				(hide yes)
			)
		)
		(property "Datasheet" ""
			(at 83.82 219.71 0)
			(effects
				(font
					(size 1.27 1.27)
					(thickness 0.15)
				)
				(justify left bottom)
				(hide yes)
			)
		)
		(property "Description" ""
			(at 74.93 207.01 0)
			(effects
				(font
					(size 1.27 1.27)
				)
				(hide yes)
			)
		)
		(property "Author" "Antmicro"
			(at 83.82 214.63 0)
			(effects
				(font
					(size 1.27 1.27)
					(thickness 0.15)
				)
				(justify left bottom)
				(hide yes)
			)
		)
		(property "License" "Apache-2.0"
			(at 83.82 217.17 0)
			(effects
				(font
					(size 1.27 1.27)
					(thickness 0.15)
				)
				(justify left bottom)
				(hide yes)
			)
		)
		(pin "1"
		)
		(instances
			(project "com-express-7-baseboard"
				(path ""
					(reference "#PWR0283")
					(unit 1)
				)
			)
		)
	)
	(symbol
		(lib_id "antmicroResistors0402:R_0R_0402")
		(at 158.75 88.9 0)
		(unit 1)
		(exclude_from_sim no)
		(in_bom yes)
		(on_board yes)
		(dnp no)
		(property "Reference" "R200"
			(at 156.21 87.63 0)
			(effects
				(font
					(size 1.27 1.27)
					(thickness 0.15)
				)
			)
		)
		(property "Value" "R_0R_0402"
			(at 179.07 101.6 0)
			(effects
				(font
					(size 1.27 1.27)
					(thickness 0.15)
				)
				(justify left bottom)
				(hide yes)
			)
		)
		(property "Footprint" "antmicro-footprints:R_0402_1005Metric"
			(at 179.07 104.14 0)
			(effects
				(font
					(size 1.27 1.27)
					(thickness 0.15)
				)
				(justify left bottom)
				(hide yes)
			)
		)
		(property "Datasheet" "https://industrial.panasonic.com/cdbs/www-data/pdf/RDA0000/AOA0000C301.pdf"
			(at 179.07 106.68 0)
			(effects
				(font
					(size 1.27 1.27)
					(thickness 0.15)
				)
				(justify left bottom)
				(hide yes)
			)
		)
		(property "Description" ""
			(at 158.75 88.9 0)
			(effects
				(font
					(size 1.27 1.27)
				)
				(hide yes)
			)
		)
		(property "MPN" "ERJ2GE0R00X"
			(at 179.07 109.22 0)
			(effects
				(font
					(size 1.27 1.27)
					(thickness 0.15)
				)
				(justify left bottom)
				(hide yes)
			)
		)
		(property "Manufacturer" "Panasonic"
			(at 179.07 111.76 0)
			(effects
				(font
					(size 1.27 1.27)
					(thickness 0.15)
				)
				(justify left bottom)
				(hide yes)
			)
		)
		(property "License" "Apache-2.0"
			(at 179.07 114.3 0)
			(effects
				(font
					(size 1.27 1.27)
					(thickness 0.15)
				)
				(justify left bottom)
				(hide yes)
			)
		)
		(property "Author" "Antmicro"
			(at 179.07 116.84 0)
			(effects
				(font
					(size 1.27 1.27)
					(thickness 0.15)
				)
				(justify left bottom)
				(hide yes)
			)
		)
		(property "Val" "0R"
			(at 165.1 87.63 0)
			(effects
				(font
					(size 1.27 1.27)
					(thickness 0.15)
				)
			)
		)
		(property "Tolerance" "~"
			(at 179.07 99.06 0)
			(effects
				(font
					(size 1.27 1.27)
				)
				(justify left bottom)
				(hide yes)
			)
		)
		(property "Current" "1A"
			(at 179.07 119.38 0)
			(effects
				(font
					(size 1.27 1.27)
					(thickness 0.15)
				)
				(justify left bottom)
				(hide yes)
			)
		)
		(property "Public" "False"
			(at 179.07 119.38 0)
			(effects
				(font
					(size 1.27 1.27)
				)
				(justify left bottom)
				(hide yes)
			)
		)
		(pin "1"
		)
		(pin "2"
		)
		(instances
			(project "com-express-7-baseboard"
				(path ""
					(reference "R200")
					(unit 1)
				)
			)
		)
	)
	(symbol
		(lib_id "antmicropower:GND")
		(at 82.55 57.15 0)
		(unit 1)
		(exclude_from_sim no)
		(in_bom yes)
		(on_board yes)
		(dnp no)
		(property "Reference" "#PWR0266"
			(at 82.55 63.5 0)
			(effects
				(font
					(size 1.27 1.27)
				)
				(justify left bottom)
				(hide yes)
			)
		)
		(property "Value" "GND"
			(at 80.645 62.23 0)
			(effects
				(font
					(size 1.27 1.27)
				)
				(justify left bottom)
			)
		)
		(property "Footprint" ""
			(at 82.55 57.15 0)
			(effects
				(font
					(size 1.27 1.27)
				)
				(justify left bottom)
				(hide yes)
			)
		)
		(property "Datasheet" ""
			(at 82.55 57.15 0)
			(effects
				(font
					(size 1.27 1.27)
				)
				(justify left bottom)
				(hide yes)
			)
		)
		(property "Description" ""
			(at 82.55 57.15 0)
			(effects
				(font
					(size 1.27 1.27)
				)
				(hide yes)
			)
		)
		(property "Author" "Antmicro"
			(at 91.44 64.77 0)
			(effects
				(font
					(size 1.27 1.27)
					(thickness 0.15)
				)
				(justify left bottom)
				(hide yes)
			)
		)
		(property "License" "Apache-2.0"
			(at 91.44 67.31 0)
			(effects
				(font
					(size 1.27 1.27)
					(thickness 0.15)
				)
				(justify left bottom)
				(hide yes)
			)
		)
		(pin "1"
		)
		(instances
			(project "com-express-7-baseboard"
				(path ""
					(reference "#PWR0266")
					(unit 1)
				)
			)
		)
	)
	(symbol
		(lib_id "antmicroResistors0402:R_1k_0402")
		(at 67.31 102.87 270)
		(unit 1)
		(exclude_from_sim no)
		(in_bom yes)
		(on_board yes)
		(dnp no)
		(property "Reference" "R184"
			(at 66.04 102.87 90)
			(effects
				(font
					(size 1.27 1.27)
					(thickness 0.15)
				)
				(justify right)
			)
		)
		(property "Value" "R_1k_0402"
			(at 54.61 123.19 0)
			(effects
				(font
					(size 1.27 1.27)
					(thickness 0.15)
				)
				(justify left bottom)
				(hide yes)
			)
		)
		(property "Footprint" "antmicro-footprints:R_0402_1005Metric"
			(at 52.07 123.19 0)
			(effects
				(font
					(size 1.27 1.27)
					(thickness 0.15)
				)
				(justify left bottom)
				(hide yes)
			)
		)
		(property "Datasheet" "https://www.bourns.com/docs/product-datasheets/cr.pdf"
			(at 49.53 123.19 0)
			(effects
				(font
					(size 1.27 1.27)
					(thickness 0.15)
				)
				(justify left bottom)
				(hide yes)
			)
		)
		(property "Description" ""
			(at 67.31 102.87 0)
			(effects
				(font
					(size 1.27 1.27)
				)
				(hide yes)
			)
		)
		(property "MPN" "CR0402-FX-1001GLF"
			(at 46.99 123.19 0)
			(effects
				(font
					(size 1.27 1.27)
					(thickness 0.15)
				)
				(justify left bottom)
				(hide yes)
			)
		)
		(property "Manufacturer" "Bourns"
			(at 44.45 123.19 0)
			(effects
				(font
					(size 1.27 1.27)
					(thickness 0.15)
				)
				(justify left bottom)
				(hide yes)
			)
		)
		(property "License" "Apache-2.0"
			(at 41.91 123.19 0)
			(effects
				(font
					(size 1.27 1.27)
					(thickness 0.15)
				)
				(justify left bottom)
				(hide yes)
			)
		)
		(property "Author" "Antmicro"
			(at 39.37 123.19 0)
			(effects
				(font
					(size 1.27 1.27)
					(thickness 0.15)
				)
				(justify left bottom)
				(hide yes)
			)
		)
		(property "Val" "1k"
			(at 66.04 105.41 90)
			(effects
				(font
					(size 1.27 1.27)
					(thickness 0.15)
				)
				(justify right)
			)
		)
		(property "Tolerance" "1%"
			(at 57.15 123.19 0)
			(effects
				(font
					(size 1.27 1.27)
				)
				(justify left bottom)
				(hide yes)
			)
		)
		(property "Public" "False"
			(at 36.83 123.19 0)
			(effects
				(font
					(size 1.27 1.27)
				)
				(justify left bottom)
				(hide yes)
			)
		)
		(pin "2"
		)
		(pin "1"
		)
		(instances
			(project "com-express-7-baseboard"
				(path ""
					(reference "R184")
					(unit 1)
				)
			)
		)
	)
	(symbol
		(lib_id "antmicroResistors0402:R_1k_0402")
		(at 80.01 102.87 270)
		(unit 1)
		(exclude_from_sim no)
		(in_bom yes)
		(on_board yes)
		(dnp no)
		(property "Reference" "R186"
			(at 78.74 102.87 90)
			(effects
				(font
					(size 1.27 1.27)
					(thickness 0.15)
				)
				(justify right)
			)
		)
		(property "Value" "R_1k_0402"
			(at 67.31 123.19 0)
			(effects
				(font
					(size 1.27 1.27)
					(thickness 0.15)
				)
				(justify left bottom)
				(hide yes)
			)
		)
		(property "Footprint" "antmicro-footprints:R_0402_1005Metric"
			(at 64.77 123.19 0)
			(effects
				(font
					(size 1.27 1.27)
					(thickness 0.15)
				)
				(justify left bottom)
				(hide yes)
			)
		)
		(property "Datasheet" "https://www.bourns.com/docs/product-datasheets/cr.pdf"
			(at 62.23 123.19 0)
			(effects
				(font
					(size 1.27 1.27)
					(thickness 0.15)
				)
				(justify left bottom)
				(hide yes)
			)
		)
		(property "Description" ""
			(at 80.01 102.87 0)
			(effects
				(font
					(size 1.27 1.27)
				)
				(hide yes)
			)
		)
		(property "MPN" "CR0402-FX-1001GLF"
			(at 59.69 123.19 0)
			(effects
				(font
					(size 1.27 1.27)
					(thickness 0.15)
				)
				(justify left bottom)
				(hide yes)
			)
		)
		(property "Manufacturer" "Bourns"
			(at 57.15 123.19 0)
			(effects
				(font
					(size 1.27 1.27)
					(thickness 0.15)
				)
				(justify left bottom)
				(hide yes)
			)
		)
		(property "License" "Apache-2.0"
			(at 54.61 123.19 0)
			(effects
				(font
					(size 1.27 1.27)
					(thickness 0.15)
				)
				(justify left bottom)
				(hide yes)
			)
		)
		(property "Author" "Antmicro"
			(at 52.07 123.19 0)
			(effects
				(font
					(size 1.27 1.27)
					(thickness 0.15)
				)
				(justify left bottom)
				(hide yes)
			)
		)
		(property "Val" "1k"
			(at 78.74 105.41 90)
			(effects
				(font
					(size 1.27 1.27)
					(thickness 0.15)
				)
				(justify right)
			)
		)
		(property "Tolerance" "1%"
			(at 69.85 123.19 0)
			(effects
				(font
					(size 1.27 1.27)
				)
				(justify left bottom)
				(hide yes)
			)
		)
		(property "Public" "False"
			(at 49.53 123.19 0)
			(effects
				(font
					(size 1.27 1.27)
				)
				(justify left bottom)
				(hide yes)
			)
		)
		(pin "2"
		)
		(pin "1"
		)
		(instances
			(project "com-express-7-baseboard"
				(path ""
					(reference "R186")
					(unit 1)
				)
			)
		)
	)
	(symbol
		(lib_id "antmicroResistors0402:R_0R_0402")
		(at 158.75 83.82 0)
		(unit 1)
		(exclude_from_sim no)
		(in_bom yes)
		(on_board yes)
		(dnp no)
		(property "Reference" "R199"
			(at 156.21 82.55 0)
			(effects
				(font
					(size 1.27 1.27)
					(thickness 0.15)
				)
			)
		)
		(property "Value" "R_0R_0402"
			(at 179.07 96.52 0)
			(effects
				(font
					(size 1.27 1.27)
					(thickness 0.15)
				)
				(justify left bottom)
				(hide yes)
			)
		)
		(property "Footprint" "antmicro-footprints:R_0402_1005Metric"
			(at 179.07 99.06 0)
			(effects
				(font
					(size 1.27 1.27)
					(thickness 0.15)
				)
				(justify left bottom)
				(hide yes)
			)
		)
		(property "Datasheet" "https://industrial.panasonic.com/cdbs/www-data/pdf/RDA0000/AOA0000C301.pdf"
			(at 179.07 101.6 0)
			(effects
				(font
					(size 1.27 1.27)
					(thickness 0.15)
				)
				(justify left bottom)
				(hide yes)
			)
		)
		(property "Description" ""
			(at 158.75 83.82 0)
			(effects
				(font
					(size 1.27 1.27)
				)
				(hide yes)
			)
		)
		(property "MPN" "ERJ2GE0R00X"
			(at 179.07 104.14 0)
			(effects
				(font
					(size 1.27 1.27)
					(thickness 0.15)
				)
				(justify left bottom)
				(hide yes)
			)
		)
		(property "Manufacturer" "Panasonic"
			(at 179.07 106.68 0)
			(effects
				(font
					(size 1.27 1.27)
					(thickness 0.15)
				)
				(justify left bottom)
				(hide yes)
			)
		)
		(property "License" "Apache-2.0"
			(at 179.07 109.22 0)
			(effects
				(font
					(size 1.27 1.27)
					(thickness 0.15)
				)
				(justify left bottom)
				(hide yes)
			)
		)
		(property "Author" "Antmicro"
			(at 179.07 111.76 0)
			(effects
				(font
					(size 1.27 1.27)
					(thickness 0.15)
				)
				(justify left bottom)
				(hide yes)
			)
		)
		(property "Val" "0R"
			(at 165.1 82.55 0)
			(effects
				(font
					(size 1.27 1.27)
					(thickness 0.15)
				)
			)
		)
		(property "Tolerance" "~"
			(at 179.07 93.98 0)
			(effects
				(font
					(size 1.27 1.27)
				)
				(justify left bottom)
				(hide yes)
			)
		)
		(property "Current" "1A"
			(at 179.07 114.3 0)
			(effects
				(font
					(size 1.27 1.27)
					(thickness 0.15)
				)
				(justify left bottom)
				(hide yes)
			)
		)
		(property "Public" "False"
			(at 179.07 114.3 0)
			(effects
				(font
					(size 1.27 1.27)
				)
				(justify left bottom)
				(hide yes)
			)
		)
		(pin "1"
		)
		(pin "2"
		)
		(instances
			(project "com-express-7-baseboard"
				(path ""
					(reference "R199")
					(unit 1)
				)
			)
		)
	)
	(symbol
		(lib_id "antmicropower:+3V3")
		(at 114.3 186.69 0)
		(unit 1)
		(exclude_from_sim no)
		(in_bom yes)
		(on_board yes)
		(dnp no)
		(fields_autoplaced yes)
		(property "Reference" "#PWR0285"
			(at 129.54 186.69 0)
			(effects
				(font
					(size 1.27 1.27)
					(thickness 0.15)
				)
				(justify left bottom)
				(hide yes)
			)
		)
		(property "Value" "+3V3"
			(at 114.3 181.61 0)
			(effects
				(font
					(size 1.27 1.27)
					(thickness 0.15)
				)
			)
		)
		(property "Footprint" ""
			(at 129.54 194.31 0)
			(effects
				(font
					(size 1.27 1.27)
					(thickness 0.15)
				)
				(justify left bottom)
				(hide yes)
			)
		)
		(property "Datasheet" ""
			(at 129.54 196.85 0)
			(effects
				(font
					(size 1.27 1.27)
					(thickness 0.15)
				)
				(justify left bottom)
				(hide yes)
			)
		)
		(property "Description" ""
			(at 114.3 186.69 0)
			(effects
				(font
					(size 1.27 1.27)
				)
				(hide yes)
			)
		)
		(property "Author" "Antmicro"
			(at 129.54 189.23 0)
			(effects
				(font
					(size 1.27 1.27)
					(thickness 0.15)
				)
				(justify left bottom)
				(hide yes)
			)
		)
		(property "License" "Apache-2.0"
			(at 129.54 191.77 0)
			(effects
				(font
					(size 1.27 1.27)
					(thickness 0.15)
				)
				(justify left bottom)
				(hide yes)
			)
		)
		(pin "1"
		)
		(instances
			(project "com-express-7-baseboard"
				(path ""
					(reference "#PWR0285")
					(unit 1)
				)
			)
		)
	)
	(symbol
		(lib_id "antmicroCapacitors0402:C_100n_0402")
		(at 73.66 57.15 90)
		(unit 1)
		(exclude_from_sim no)
		(in_bom yes)
		(on_board yes)
		(dnp no)
		(fields_autoplaced yes)
		(property "Reference" "C10"
			(at 76.2 53.3336 90)
			(effects
				(font
					(size 1.27 1.27)
					(thickness 0.15)
				)
				(justify right)
			)
		)
		(property "Value" "C_100n_0402"
			(at 83.82 36.83 0)
			(effects
				(font
					(size 1.27 1.27)
					(thickness 0.15)
				)
				(justify left bottom)
				(hide yes)
			)
		)
		(property "Footprint" "antmicro-footprints:C_0402_1005Metric"
			(at 86.36 36.83 0)
			(effects
				(font
					(size 1.27 1.27)
					(thickness 0.15)
				)
				(justify left bottom)
				(hide yes)
			)
		)
		(property "Datasheet" "https://www.murata.com/products/productdetail?partno=GRM155R61H104KE14%23"
			(at 88.9 36.83 0)
			(effects
				(font
					(size 1.27 1.27)
					(thickness 0.15)
				)
				(justify left bottom)
				(hide yes)
			)
		)
		(property "Description" ""
			(at 73.66 57.15 0)
			(effects
				(font
					(size 1.27 1.27)
				)
				(hide yes)
			)
		)
		(property "MPN" "GRM155R61H104KE14D"
			(at 91.44 36.83 0)
			(effects
				(font
					(size 1.27 1.27)
					(thickness 0.15)
				)
				(justify left bottom)
				(hide yes)
			)
		)
		(property "Manufacturer" "Murata"
			(at 93.98 36.83 0)
			(effects
				(font
					(size 1.27 1.27)
					(thickness 0.15)
				)
				(justify left bottom)
				(hide yes)
			)
		)
		(property "License" "Apache-2.0"
			(at 96.52 36.83 0)
			(effects
				(font
					(size 1.27 1.27)
					(thickness 0.15)
				)
				(justify left bottom)
				(hide yes)
			)
		)
		(property "Author" "Antmicro"
			(at 99.06 36.83 0)
			(effects
				(font
					(size 1.27 1.27)
					(thickness 0.15)
				)
				(justify left bottom)
				(hide yes)
			)
		)
		(property "Val" "100n"
			(at 76.2 55.8736 90)
			(effects
				(font
					(size 1.27 1.27)
					(thickness 0.15)
				)
				(justify right)
			)
		)
		(property "Voltage" "50V"
			(at 101.6 36.83 0)
			(effects
				(font
					(size 1.27 1.27)
				)
				(justify left bottom)
				(hide yes)
			)
		)
		(property "Dielectric" "X5R"
			(at 104.14 36.83 0)
			(effects
				(font
					(size 1.27 1.27)
				)
				(justify left bottom)
				(hide yes)
			)
		)
		(property "Public" "False"
			(at 106.68 36.83 0)
			(effects
				(font
					(size 1.27 1.27)
				)
				(justify left bottom)
				(hide yes)
			)
		)
		(pin "1"
		)
		(pin "2"
		)
		(instances
			(project "com-express-7-baseboard"
				(path ""
					(reference "C10")
					(unit 1)
				)
			)
		)
	)
	(symbol
		(lib_id "antmicroResistors0402:R_0R_0402")
		(at 40.64 88.9 0)
		(unit 1)
		(exclude_from_sim no)
		(in_bom yes)
		(on_board yes)
		(dnp yes)
		(property "Reference" "R316"
			(at 38.1 87.63 0)
			(effects
				(font
					(size 1.27 1.27)
					(thickness 0.15)
				)
			)
		)
		(property "Value" "R_0R_0402"
			(at 60.96 101.6 0)
			(effects
				(font
					(size 1.27 1.27)
					(thickness 0.15)
				)
				(justify left bottom)
				(hide yes)
			)
		)
		(property "Footprint" "antmicro-footprints:R_0402_1005Metric"
			(at 60.96 104.14 0)
			(effects
				(font
					(size 1.27 1.27)
					(thickness 0.15)
				)
				(justify left bottom)
				(hide yes)
			)
		)
		(property "Datasheet" "https://industrial.panasonic.com/cdbs/www-data/pdf/RDA0000/AOA0000C301.pdf"
			(at 60.96 106.68 0)
			(effects
				(font
					(size 1.27 1.27)
					(thickness 0.15)
				)
				(justify left bottom)
				(hide yes)
			)
		)
		(property "Description" ""
			(at 40.64 88.9 0)
			(effects
				(font
					(size 1.27 1.27)
				)
				(hide yes)
			)
		)
		(property "MPN" "ERJ2GE0R00X"
			(at 60.96 109.22 0)
			(effects
				(font
					(size 1.27 1.27)
					(thickness 0.15)
				)
				(justify left bottom)
				(hide yes)
			)
		)
		(property "Manufacturer" "Panasonic"
			(at 60.96 111.76 0)
			(effects
				(font
					(size 1.27 1.27)
					(thickness 0.15)
				)
				(justify left bottom)
				(hide yes)
			)
		)
		(property "License" "Apache-2.0"
			(at 60.96 114.3 0)
			(effects
				(font
					(size 1.27 1.27)
					(thickness 0.15)
				)
				(justify left bottom)
				(hide yes)
			)
		)
		(property "Author" "Antmicro"
			(at 60.96 116.84 0)
			(effects
				(font
					(size 1.27 1.27)
					(thickness 0.15)
				)
				(justify left bottom)
				(hide yes)
			)
		)
		(property "Val" "0R"
			(at 46.99 87.63 0)
			(effects
				(font
					(size 1.27 1.27)
					(thickness 0.15)
				)
			)
		)
		(property "Tolerance" "~"
			(at 60.96 99.06 0)
			(effects
				(font
					(size 1.27 1.27)
				)
				(justify left bottom)
				(hide yes)
			)
		)
		(property "Current" "1A"
			(at 60.96 119.38 0)
			(effects
				(font
					(size 1.27 1.27)
					(thickness 0.15)
				)
				(justify left bottom)
				(hide yes)
			)
		)
		(property "Public" "False"
			(at 60.96 119.38 0)
			(effects
				(font
					(size 1.27 1.27)
				)
				(justify left bottom)
				(hide yes)
			)
		)
		(pin "1"
		)
		(pin "2"
		)
		(instances
			(project "com-express-7-baseboard"
				(path ""
					(reference "R316")
					(unit 1)
				)
			)
		)
	)
	(symbol
		(lib_id "antmicropower:GND")
		(at 91.44 212.09 0)
		(unit 1)
		(exclude_from_sim no)
		(in_bom yes)
		(on_board yes)
		(dnp no)
		(property "Reference" "#PWR0284"
			(at 100.33 214.63 0)
			(effects
				(font
					(size 1.27 1.27)
					(thickness 0.15)
				)
				(justify left bottom)
				(hide yes)
			)
		)
		(property "Value" "GND"
			(at 91.44 215.9 0)
			(effects
				(font
					(size 1.27 1.27)
					(thickness 0.15)
				)
			)
		)
		(property "Footprint" ""
			(at 100.33 219.71 0)
			(effects
				(font
					(size 1.27 1.27)
					(thickness 0.15)
				)
				(justify left bottom)
				(hide yes)
			)
		)
		(property "Datasheet" ""
			(at 100.33 224.79 0)
			(effects
				(font
					(size 1.27 1.27)
					(thickness 0.15)
				)
				(justify left bottom)
				(hide yes)
			)
		)
		(property "Description" ""
			(at 91.44 212.09 0)
			(effects
				(font
					(size 1.27 1.27)
				)
				(hide yes)
			)
		)
		(property "Author" "Antmicro"
			(at 100.33 219.71 0)
			(effects
				(font
					(size 1.27 1.27)
					(thickness 0.15)
				)
				(justify left bottom)
				(hide yes)
			)
		)
		(property "License" "Apache-2.0"
			(at 100.33 222.25 0)
			(effects
				(font
					(size 1.27 1.27)
					(thickness 0.15)
				)
				(justify left bottom)
				(hide yes)
			)
		)
		(pin "1"
		)
		(instances
			(project "com-express-7-baseboard"
				(path ""
					(reference "#PWR0284")
					(unit 1)
				)
			)
		)
	)
	(symbol
		(lib_id "antmicroCapacitors0402:C_100n_0402")
		(at 91.44 57.15 90)
		(unit 1)
		(exclude_from_sim no)
		(in_bom yes)
		(on_board yes)
		(dnp no)
		(fields_autoplaced yes)
		(property "Reference" "C103"
			(at 93.98 53.3336 90)
			(effects
				(font
					(size 1.27 1.27)
					(thickness 0.15)
				)
				(justify right)
			)
		)
		(property "Value" "C_100n_0402"
			(at 101.6 36.83 0)
			(effects
				(font
					(size 1.27 1.27)
					(thickness 0.15)
				)
				(justify left bottom)
				(hide yes)
			)
		)
		(property "Footprint" "antmicro-footprints:C_0402_1005Metric"
			(at 104.14 36.83 0)
			(effects
				(font
					(size 1.27 1.27)
					(thickness 0.15)
				)
				(justify left bottom)
				(hide yes)
			)
		)
		(property "Datasheet" "https://www.murata.com/products/productdetail?partno=GRM155R61H104KE14%23"
			(at 106.68 36.83 0)
			(effects
				(font
					(size 1.27 1.27)
					(thickness 0.15)
				)
				(justify left bottom)
				(hide yes)
			)
		)
		(property "Description" ""
			(at 91.44 57.15 0)
			(effects
				(font
					(size 1.27 1.27)
				)
				(hide yes)
			)
		)
		(property "MPN" "GRM155R61H104KE14D"
			(at 109.22 36.83 0)
			(effects
				(font
					(size 1.27 1.27)
					(thickness 0.15)
				)
				(justify left bottom)
				(hide yes)
			)
		)
		(property "Manufacturer" "Murata"
			(at 111.76 36.83 0)
			(effects
				(font
					(size 1.27 1.27)
					(thickness 0.15)
				)
				(justify left bottom)
				(hide yes)
			)
		)
		(property "License" "Apache-2.0"
			(at 114.3 36.83 0)
			(effects
				(font
					(size 1.27 1.27)
					(thickness 0.15)
				)
				(justify left bottom)
				(hide yes)
			)
		)
		(property "Author" "Antmicro"
			(at 116.84 36.83 0)
			(effects
				(font
					(size 1.27 1.27)
					(thickness 0.15)
				)
				(justify left bottom)
				(hide yes)
			)
		)
		(property "Val" "100n"
			(at 93.98 55.8736 90)
			(effects
				(font
					(size 1.27 1.27)
					(thickness 0.15)
				)
				(justify right)
			)
		)
		(property "Voltage" "50V"
			(at 119.38 36.83 0)
			(effects
				(font
					(size 1.27 1.27)
				)
				(justify left bottom)
				(hide yes)
			)
		)
		(property "Dielectric" "X5R"
			(at 121.92 36.83 0)
			(effects
				(font
					(size 1.27 1.27)
				)
				(justify left bottom)
				(hide yes)
			)
		)
		(property "Public" "False"
			(at 124.46 36.83 0)
			(effects
				(font
					(size 1.27 1.27)
				)
				(justify left bottom)
				(hide yes)
			)
		)
		(pin "1"
		)
		(pin "2"
		)
		(instances
			(project "com-express-7-baseboard"
				(path ""
					(reference "C103")
					(unit 1)
				)
			)
		)
	)
	(symbol
		(lib_id "antmicroTestPoints:TP_0.75mm_SMD")
		(at 151.13 99.06 0)
		(mirror x)
		(unit 1)
		(exclude_from_sim no)
		(in_bom no)
		(on_board yes)
		(dnp no)
		(property "Reference" "TP48"
			(at 157.48 99.06 0)
			(effects
				(font
					(size 1.27 1.27)
					(thickness 0.15)
				)
			)
		)
		(property "Value" "TP_0.75mm_SMD"
			(at 161.925 95.25 0)
			(effects
				(font
					(size 1.27 1.27)
					(thickness 0.15)
				)
				(justify left bottom)
				(hide yes)
			)
		)
		(property "Footprint" "antmicro-footprints:TP_SMD_0.75mm"
			(at 161.925 92.71 0)
			(effects
				(font
					(size 1.27 1.27)
					(thickness 0.15)
				)
				(justify left bottom)
				(hide yes)
			)
		)
		(property "Datasheet" ""
			(at 168.91 86.36 0)
			(effects
				(font
					(size 1.27 1.27)
					(thickness 0.15)
				)
				(justify left bottom)
				(hide yes)
			)
		)
		(property "Description" ""
			(at 151.13 99.06 0)
			(effects
				(font
					(size 1.27 1.27)
				)
				(hide yes)
			)
		)
		(property "MPN" ""
			(at 161.925 87.63 0)
			(effects
				(font
					(size 1.27 1.27)
					(thickness 0.15)
				)
				(justify left bottom)
				(hide yes)
			)
		)
		(property "Manufacturer" ""
			(at 161.925 92.71 0)
			(effects
				(font
					(size 1.27 1.27)
					(thickness 0.15)
				)
				(justify left bottom)
				(hide yes)
			)
		)
		(property "Author" "Antmicro"
			(at 161.925 90.17 0)
			(effects
				(font
					(size 1.27 1.27)
					(thickness 0.15)
				)
				(justify left bottom)
				(hide yes)
			)
		)
		(property "License" "Apache-2.0"
			(at 161.925 87.63 0)
			(effects
				(font
					(size 1.27 1.27)
					(thickness 0.15)
				)
				(justify left bottom)
				(hide yes)
			)
		)
		(property "Public" "False"
			(at 161.29 85.09 0)
			(effects
				(font
					(size 1.27 1.27)
				)
				(justify left bottom)
				(hide yes)
			)
		)
		(pin "1"
		)
		(instances
			(project "com-express-7-baseboard"
				(path ""
					(reference "TP48")
					(unit 1)
				)
			)
		)
	)
	(symbol
		(lib_id "antmicroCapacitors0402:C_100n_0402")
		(at 114.3 194.31 90)
		(unit 1)
		(exclude_from_sim no)
		(in_bom yes)
		(on_board yes)
		(dnp no)
		(property "Reference" "C110"
			(at 116.84 190.4936 90)
			(effects
				(font
					(size 1.27 1.27)
					(thickness 0.15)
				)
				(justify right)
			)
		)
		(property "Value" "C_100n_0402"
			(at 124.46 173.99 0)
			(effects
				(font
					(size 1.27 1.27)
					(thickness 0.15)
				)
				(justify left bottom)
				(hide yes)
			)
		)
		(property "Footprint" "antmicro-footprints:C_0402_1005Metric"
			(at 127 173.99 0)
			(effects
				(font
					(size 1.27 1.27)
					(thickness 0.15)
				)
				(justify left bottom)
				(hide yes)
			)
		)
		(property "Datasheet" "https://www.murata.com/products/productdetail?partno=GRM155R61H104KE14%23"
			(at 129.54 173.99 0)
			(effects
				(font
					(size 1.27 1.27)
					(thickness 0.15)
				)
				(justify left bottom)
				(hide yes)
			)
		)
		(property "Description" ""
			(at 114.3 194.31 0)
			(effects
				(font
					(size 1.27 1.27)
				)
				(hide yes)
			)
		)
		(property "MPN" "GRM155R61H104KE14D"
			(at 132.08 173.99 0)
			(effects
				(font
					(size 1.27 1.27)
					(thickness 0.15)
				)
				(justify left bottom)
				(hide yes)
			)
		)
		(property "Manufacturer" "Murata"
			(at 134.62 173.99 0)
			(effects
				(font
					(size 1.27 1.27)
					(thickness 0.15)
				)
				(justify left bottom)
				(hide yes)
			)
		)
		(property "License" "Apache-2.0"
			(at 137.16 173.99 0)
			(effects
				(font
					(size 1.27 1.27)
					(thickness 0.15)
				)
				(justify left bottom)
				(hide yes)
			)
		)
		(property "Author" "Antmicro"
			(at 139.7 173.99 0)
			(effects
				(font
					(size 1.27 1.27)
					(thickness 0.15)
				)
				(justify left bottom)
				(hide yes)
			)
		)
		(property "Val" "100n"
			(at 116.84 193.0336 90)
			(effects
				(font
					(size 1.27 1.27)
					(thickness 0.15)
				)
				(justify right)
			)
		)
		(property "Voltage" "50V"
			(at 142.24 173.99 0)
			(effects
				(font
					(size 1.27 1.27)
				)
				(justify left bottom)
				(hide yes)
			)
		)
		(property "Dielectric" "X5R"
			(at 144.78 173.99 0)
			(effects
				(font
					(size 1.27 1.27)
				)
				(justify left bottom)
				(hide yes)
			)
		)
		(property "Public" "False"
			(at 147.32 173.99 0)
			(effects
				(font
					(size 1.27 1.27)
				)
				(justify left bottom)
				(hide yes)
			)
		)
		(pin "1"
		)
		(pin "2"
		)
		(instances
			(project "com-express-7-baseboard"
				(path ""
					(reference "C110")
					(unit 1)
				)
			)
		)
	)
	(symbol
		(lib_id "antmicroClockTimingClockGeneratorsPLLsFrequencySynthesizers:9DBL0651CKILF")
		(at 111.76 58.42 0)
		(unit 1)
		(exclude_from_sim no)
		(in_bom yes)
		(on_board yes)
		(dnp no)
		(fields_autoplaced yes)
		(property "Reference" "U37"
			(at 127 50.8 0)
			(effects
				(font
					(size 1.27 1.27)
					(thickness 0.15)
				)
			)
		)
		(property "Value" "9DBL0651CKILF"
			(at 157.48 68.58 0)
			(effects
				(font
					(size 1.27 1.27)
					(thickness 0.15)
				)
				(justify left bottom)
				(hide yes)
			)
		)
		(property "Footprint" "antmicro-footprints:VFQFPN-40-1EP_5x5mm_P0.4mm_EP3.5x3.5mm"
			(at 157.48 71.12 0)
			(effects
				(font
					(size 1.27 1.27)
					(thickness 0.15)
				)
				(justify left bottom)
				(hide yes)
			)
		)
		(property "Datasheet" "https://eu.mouser.com/datasheet/2/698/REN_9DBL02x2_9DBL04x2_9DBL06x1_9DBL08x1C_DST_20221-3075841.pdf"
			(at 157.48 73.66 0)
			(effects
				(font
					(size 1.27 1.27)
					(thickness 0.15)
				)
				(justify left bottom)
				(hide yes)
			)
		)
		(property "Description" ""
			(at 111.76 58.42 0)
			(effects
				(font
					(size 1.27 1.27)
				)
				(hide yes)
			)
		)
		(property "MPN" "9DBL0651CKILF"
			(at 127 53.34 0)
			(effects
				(font
					(size 1.27 1.27)
					(thickness 0.15)
				)
			)
		)
		(property "Manufacturer" "Renesas"
			(at 127 53.34 0)
			(effects
				(font
					(size 1.27 1.27)
					(thickness 0.15)
				)
				(hide yes)
			)
		)
		(property "Author" "Antmicro"
			(at 157.48 76.2 0)
			(effects
				(font
					(size 1.27 1.27)
					(thickness 0.15)
				)
				(justify left bottom)
				(hide yes)
			)
		)
		(property "License" "Apache-2.0"
			(at 157.48 78.74 0)
			(effects
				(font
					(size 1.27 1.27)
					(thickness 0.15)
				)
				(justify left bottom)
				(hide yes)
			)
		)
		(pin "7"
		)
		(pin "17"
		)
		(pin "25"
		)
		(pin "26"
		)
		(pin "27"
		)
		(pin "6"
		)
		(pin "5"
		)
		(pin "41"
		)
		(pin "9"
		)
		(pin "23"
		)
		(pin "30"
		)
		(pin "22"
		)
		(pin "21"
		)
		(pin "31"
		)
		(pin "19"
		)
		(pin "38"
		)
		(pin "20"
		)
		(pin "28"
		)
		(pin "37"
		)
		(pin "24"
		)
		(pin "8"
		)
		(pin "32"
		)
		(pin "33"
		)
		(pin "35"
		)
		(pin "39"
		)
		(pin "2"
		)
		(pin "18"
		)
		(pin "40"
		)
		(pin "16"
		)
		(pin "34"
		)
		(pin "36"
		)
		(pin "3"
		)
		(pin "29"
		)
		(pin "4"
		)
		(pin "10"
		)
		(pin "1"
		)
		(pin "11"
		)
		(pin "12"
		)
		(pin "13"
		)
		(pin "14"
		)
		(pin "15"
		)
		(instances
			(project "com-express-7-baseboard"
				(path ""
					(reference "U37")
					(unit 1)
				)
			)
		)
	)
	(symbol
		(lib_id "antmicroResistors0402:R_0R_0402")
		(at 158.75 58.42 0)
		(unit 1)
		(exclude_from_sim no)
		(in_bom yes)
		(on_board yes)
		(dnp no)
		(property "Reference" "R192"
			(at 156.21 57.15 0)
			(effects
				(font
					(size 1.27 1.27)
					(thickness 0.15)
				)
			)
		)
		(property "Value" "R_0R_0402"
			(at 179.07 71.12 0)
			(effects
				(font
					(size 1.27 1.27)
					(thickness 0.15)
				)
				(justify left bottom)
				(hide yes)
			)
		)
		(property "Footprint" "antmicro-footprints:R_0402_1005Metric"
			(at 179.07 73.66 0)
			(effects
				(font
					(size 1.27 1.27)
					(thickness 0.15)
				)
				(justify left bottom)
				(hide yes)
			)
		)
		(property "Datasheet" "https://industrial.panasonic.com/cdbs/www-data/pdf/RDA0000/AOA0000C301.pdf"
			(at 179.07 76.2 0)
			(effects
				(font
					(size 1.27 1.27)
					(thickness 0.15)
				)
				(justify left bottom)
				(hide yes)
			)
		)
		(property "Description" ""
			(at 158.75 58.42 0)
			(effects
				(font
					(size 1.27 1.27)
				)
				(hide yes)
			)
		)
		(property "MPN" "ERJ2GE0R00X"
			(at 179.07 78.74 0)
			(effects
				(font
					(size 1.27 1.27)
					(thickness 0.15)
				)
				(justify left bottom)
				(hide yes)
			)
		)
		(property "Manufacturer" "Panasonic"
			(at 179.07 81.28 0)
			(effects
				(font
					(size 1.27 1.27)
					(thickness 0.15)
				)
				(justify left bottom)
				(hide yes)
			)
		)
		(property "License" "Apache-2.0"
			(at 179.07 83.82 0)
			(effects
				(font
					(size 1.27 1.27)
					(thickness 0.15)
				)
				(justify left bottom)
				(hide yes)
			)
		)
		(property "Author" "Antmicro"
			(at 179.07 86.36 0)
			(effects
				(font
					(size 1.27 1.27)
					(thickness 0.15)
				)
				(justify left bottom)
				(hide yes)
			)
		)
		(property "Val" "0R"
			(at 165.1 57.15 0)
			(effects
				(font
					(size 1.27 1.27)
					(thickness 0.15)
				)
			)
		)
		(property "Tolerance" "~"
			(at 179.07 68.58 0)
			(effects
				(font
					(size 1.27 1.27)
				)
				(justify left bottom)
				(hide yes)
			)
		)
		(property "Current" "1A"
			(at 179.07 88.9 0)
			(effects
				(font
					(size 1.27 1.27)
					(thickness 0.15)
				)
				(justify left bottom)
				(hide yes)
			)
		)
		(property "Public" "False"
			(at 179.07 88.9 0)
			(effects
				(font
					(size 1.27 1.27)
				)
				(justify left bottom)
				(hide yes)
			)
		)
		(pin "1"
		)
		(pin "2"
		)
		(instances
			(project "com-express-7-baseboard"
				(path ""
					(reference "R192")
					(unit 1)
				)
			)
		)
	)
	(symbol
		(lib_id "antmicroOscillators:Oscillator_32.768kHz_ECS_2520MV")
		(at 92.71 205.74 0)
		(unit 1)
		(exclude_from_sim no)
		(in_bom yes)
		(on_board yes)
		(dnp no)
		(property "Reference" "Y1"
			(at 107.95 201.93 0)
			(effects
				(font
					(size 1.27 1.27)
					(thickness 0.15)
				)
			)
		)
		(property "Value" "Oscillator_32.768kHz_ECS_2520MV"
			(at 118.745 218.44 0)
			(effects
				(font
					(size 1.27 1.27)
					(thickness 0.15)
				)
				(justify left bottom)
				(hide yes)
			)
		)
		(property "Footprint" "antmicro-footprints:Oscillator_SMD_ECS_2520MV_2.5x2mm"
			(at 118.745 220.98 0)
			(effects
				(font
					(size 1.27 1.27)
					(thickness 0.15)
				)
				(justify left bottom)
				(hide yes)
			)
		)
		(property "Datasheet" "https://ecsxtal.com/store/pdf/ECS-327MVATX.pdf"
			(at 118.745 223.52 0)
			(effects
				(font
					(size 1.27 1.27)
					(thickness 0.15)
				)
				(justify left bottom)
				(hide yes)
			)
		)
		(property "Description" ""
			(at 92.71 205.74 0)
			(effects
				(font
					(size 1.27 1.27)
				)
				(hide yes)
			)
		)
		(property "Manufacturer" "ECS Inc. International"
			(at 118.745 213.36 0)
			(effects
				(font
					(size 1.27 1.27)
					(thickness 0.15)
				)
				(justify left bottom)
				(hide yes)
			)
		)
		(property "MPN" "ECS-327MVATX-2-CN-TR3"
			(at 102.87 219.71 0)
			(effects
				(font
					(size 1.27 1.27)
					(thickness 0.15)
				)
			)
		)
		(property "Val" "32.768 kHz"
			(at 101.6 217.17 0)
			(effects
				(font
					(size 1.27 1.27)
					(thickness 0.15)
				)
			)
		)
		(property "Author" "Antmicro"
			(at 118.745 226.06 0)
			(effects
				(font
					(size 1.27 1.27)
					(thickness 0.15)
				)
				(justify left bottom)
				(hide yes)
			)
		)
		(property "License" "Apache-2.0"
			(at 118.745 228.6 0)
			(effects
				(font
					(size 1.27 1.27)
					(thickness 0.15)
				)
				(justify left bottom)
				(hide yes)
			)
		)
		(property "Public" "False"
			(at 124.46 229.87 0)
			(effects
				(font
					(size 1.27 1.27)
				)
				(justify left bottom)
				(hide yes)
			)
		)
		(pin "1"
		)
		(pin "2"
		)
		(pin "3"
		)
		(pin "4"
		)
		(instances
			(project "com-express-7-baseboard"
				(path ""
					(reference "Y1")
					(unit 1)
				)
			)
		)
	)
	(symbol
		(lib_id "antmicroResistors0402:R_0R_0402")
		(at 158.75 91.44 0)
		(unit 1)
		(exclude_from_sim no)
		(in_bom yes)
		(on_board yes)
		(dnp no)
		(property "Reference" "R201"
			(at 156.21 90.17 0)
			(effects
				(font
					(size 1.27 1.27)
					(thickness 0.15)
				)
			)
		)
		(property "Value" "R_0R_0402"
			(at 179.07 104.14 0)
			(effects
				(font
					(size 1.27 1.27)
					(thickness 0.15)
				)
				(justify left bottom)
				(hide yes)
			)
		)
		(property "Footprint" "antmicro-footprints:R_0402_1005Metric"
			(at 179.07 106.68 0)
			(effects
				(font
					(size 1.27 1.27)
					(thickness 0.15)
				)
				(justify left bottom)
				(hide yes)
			)
		)
		(property "Datasheet" "https://industrial.panasonic.com/cdbs/www-data/pdf/RDA0000/AOA0000C301.pdf"
			(at 179.07 109.22 0)
			(effects
				(font
					(size 1.27 1.27)
					(thickness 0.15)
				)
				(justify left bottom)
				(hide yes)
			)
		)
		(property "Description" ""
			(at 158.75 91.44 0)
			(effects
				(font
					(size 1.27 1.27)
				)
				(hide yes)
			)
		)
		(property "MPN" "ERJ2GE0R00X"
			(at 179.07 111.76 0)
			(effects
				(font
					(size 1.27 1.27)
					(thickness 0.15)
				)
				(justify left bottom)
				(hide yes)
			)
		)
		(property "Manufacturer" "Panasonic"
			(at 179.07 114.3 0)
			(effects
				(font
					(size 1.27 1.27)
					(thickness 0.15)
				)
				(justify left bottom)
				(hide yes)
			)
		)
		(property "License" "Apache-2.0"
			(at 179.07 116.84 0)
			(effects
				(font
					(size 1.27 1.27)
					(thickness 0.15)
				)
				(justify left bottom)
				(hide yes)
			)
		)
		(property "Author" "Antmicro"
			(at 179.07 119.38 0)
			(effects
				(font
					(size 1.27 1.27)
					(thickness 0.15)
				)
				(justify left bottom)
				(hide yes)
			)
		)
		(property "Val" "0R"
			(at 165.1 90.17 0)
			(effects
				(font
					(size 1.27 1.27)
					(thickness 0.15)
				)
			)
		)
		(property "Tolerance" "~"
			(at 179.07 101.6 0)
			(effects
				(font
					(size 1.27 1.27)
				)
				(justify left bottom)
				(hide yes)
			)
		)
		(property "Current" "1A"
			(at 179.07 121.92 0)
			(effects
				(font
					(size 1.27 1.27)
					(thickness 0.15)
				)
				(justify left bottom)
				(hide yes)
			)
		)
		(property "Public" "False"
			(at 179.07 121.92 0)
			(effects
				(font
					(size 1.27 1.27)
				)
				(justify left bottom)
				(hide yes)
			)
		)
		(pin "1"
		)
		(pin "2"
		)
		(instances
			(project "com-express-7-baseboard"
				(path ""
					(reference "R201")
					(unit 1)
				)
			)
		)
	)
	(symbol
		(lib_id "antmicropower:GND")
		(at 80.01 109.22 0)
		(unit 1)
		(exclude_from_sim no)
		(in_bom yes)
		(on_board yes)
		(dnp no)
		(property "Reference" "#PWR0277"
			(at 88.9 111.76 0)
			(effects
				(font
					(size 1.27 1.27)
					(thickness 0.15)
				)
				(justify left bottom)
				(hide yes)
			)
		)
		(property "Value" "GND"
			(at 80.01 113.03 0)
			(effects
				(font
					(size 1.27 1.27)
					(thickness 0.15)
				)
			)
		)
		(property "Footprint" ""
			(at 88.9 116.84 0)
			(effects
				(font
					(size 1.27 1.27)
					(thickness 0.15)
				)
				(justify left bottom)
				(hide yes)
			)
		)
		(property "Datasheet" ""
			(at 88.9 121.92 0)
			(effects
				(font
					(size 1.27 1.27)
					(thickness 0.15)
				)
				(justify left bottom)
				(hide yes)
			)
		)
		(property "Description" ""
			(at 80.01 109.22 0)
			(effects
				(font
					(size 1.27 1.27)
				)
				(hide yes)
			)
		)
		(property "Author" "Antmicro"
			(at 88.9 116.84 0)
			(effects
				(font
					(size 1.27 1.27)
					(thickness 0.15)
				)
				(justify left bottom)
				(hide yes)
			)
		)
		(property "License" "Apache-2.0"
			(at 88.9 119.38 0)
			(effects
				(font
					(size 1.27 1.27)
					(thickness 0.15)
				)
				(justify left bottom)
				(hide yes)
			)
		)
		(pin "1"
		)
		(instances
			(project "com-express-7-baseboard"
				(path ""
					(reference "#PWR0277")
					(unit 1)
				)
			)
		)
	)
	(symbol
		(lib_id "antmicropower:GND")
		(at 91.44 57.15 0)
		(unit 1)
		(exclude_from_sim no)
		(in_bom yes)
		(on_board yes)
		(dnp no)
		(property "Reference" "#PWR0267"
			(at 91.44 63.5 0)
			(effects
				(font
					(size 1.27 1.27)
				)
				(justify left bottom)
				(hide yes)
			)
		)
		(property "Value" "GND"
			(at 89.535 62.23 0)
			(effects
				(font
					(size 1.27 1.27)
				)
				(justify left bottom)
			)
		)
		(property "Footprint" ""
			(at 91.44 57.15 0)
			(effects
				(font
					(size 1.27 1.27)
				)
				(justify left bottom)
				(hide yes)
			)
		)
		(property "Datasheet" ""
			(at 91.44 57.15 0)
			(effects
				(font
					(size 1.27 1.27)
				)
				(justify left bottom)
				(hide yes)
			)
		)
		(property "Description" ""
			(at 91.44 57.15 0)
			(effects
				(font
					(size 1.27 1.27)
				)
				(hide yes)
			)
		)
		(property "Author" "Antmicro"
			(at 100.33 64.77 0)
			(effects
				(font
					(size 1.27 1.27)
					(thickness 0.15)
				)
				(justify left bottom)
				(hide yes)
			)
		)
		(property "License" "Apache-2.0"
			(at 100.33 67.31 0)
			(effects
				(font
					(size 1.27 1.27)
					(thickness 0.15)
				)
				(justify left bottom)
				(hide yes)
			)
		)
		(pin "1"
		)
		(instances
			(project "com-express-7-baseboard"
				(path ""
					(reference "#PWR0267")
					(unit 1)
				)
			)
		)
	)
	(symbol
		(lib_id "antmicropower:GND")
		(at 45.72 57.15 0)
		(unit 1)
		(exclude_from_sim no)
		(in_bom yes)
		(on_board yes)
		(dnp no)
		(property "Reference" "#PWR0275"
			(at 45.72 63.5 0)
			(effects
				(font
					(size 1.27 1.27)
				)
				(justify left bottom)
				(hide yes)
			)
		)
		(property "Value" "GND"
			(at 43.815 62.23 0)
			(effects
				(font
					(size 1.27 1.27)
				)
				(justify left bottom)
			)
		)
		(property "Footprint" ""
			(at 45.72 57.15 0)
			(effects
				(font
					(size 1.27 1.27)
				)
				(justify left bottom)
				(hide yes)
			)
		)
		(property "Datasheet" ""
			(at 45.72 57.15 0)
			(effects
				(font
					(size 1.27 1.27)
				)
				(justify left bottom)
				(hide yes)
			)
		)
		(property "Description" ""
			(at 45.72 57.15 0)
			(effects
				(font
					(size 1.27 1.27)
				)
				(hide yes)
			)
		)
		(property "Author" "Antmicro"
			(at 54.61 64.77 0)
			(effects
				(font
					(size 1.27 1.27)
					(thickness 0.15)
				)
				(justify left bottom)
				(hide yes)
			)
		)
		(property "License" "Apache-2.0"
			(at 54.61 67.31 0)
			(effects
				(font
					(size 1.27 1.27)
					(thickness 0.15)
				)
				(justify left bottom)
				(hide yes)
			)
		)
		(pin "1"
		)
		(instances
			(project "com-express-7-baseboard"
				(path ""
					(reference "#PWR0275")
					(unit 1)
				)
			)
		)
	)
	(symbol
		(lib_id "antmicroTestPoints:TP_0.75mm_SMD")
		(at 107.95 109.22 180)
		(unit 1)
		(exclude_from_sim no)
		(in_bom no)
		(on_board yes)
		(dnp no)
		(property "Reference" "TP46"
			(at 101.6 109.22 0)
			(effects
				(font
					(size 1.27 1.27)
					(thickness 0.15)
				)
			)
		)
		(property "Value" "TP_0.75mm_SMD"
			(at 97.155 105.41 0)
			(effects
				(font
					(size 1.27 1.27)
					(thickness 0.15)
				)
				(justify left bottom)
				(hide yes)
			)
		)
		(property "Footprint" "antmicro-footprints:TP_SMD_0.75mm"
			(at 97.155 102.87 0)
			(effects
				(font
					(size 1.27 1.27)
					(thickness 0.15)
				)
				(justify left bottom)
				(hide yes)
			)
		)
		(property "Datasheet" ""
			(at 90.17 96.52 0)
			(effects
				(font
					(size 1.27 1.27)
					(thickness 0.15)
				)
				(justify left bottom)
				(hide yes)
			)
		)
		(property "Description" ""
			(at 107.95 109.22 0)
			(effects
				(font
					(size 1.27 1.27)
				)
				(hide yes)
			)
		)
		(property "MPN" ""
			(at 97.155 97.79 0)
			(effects
				(font
					(size 1.27 1.27)
					(thickness 0.15)
				)
				(justify left bottom)
				(hide yes)
			)
		)
		(property "Manufacturer" ""
			(at 97.155 102.87 0)
			(effects
				(font
					(size 1.27 1.27)
					(thickness 0.15)
				)
				(justify left bottom)
				(hide yes)
			)
		)
		(property "Author" "Antmicro"
			(at 97.155 100.33 0)
			(effects
				(font
					(size 1.27 1.27)
					(thickness 0.15)
				)
				(justify left bottom)
				(hide yes)
			)
		)
		(property "License" "Apache-2.0"
			(at 97.155 97.79 0)
			(effects
				(font
					(size 1.27 1.27)
					(thickness 0.15)
				)
				(justify left bottom)
				(hide yes)
			)
		)
		(property "Public" "False"
			(at 97.79 95.25 0)
			(effects
				(font
					(size 1.27 1.27)
				)
				(justify left bottom)
				(hide yes)
			)
		)
		(pin "1"
		)
		(instances
			(project "com-express-7-baseboard"
				(path ""
					(reference "TP46")
					(unit 1)
				)
			)
		)
	)
	(symbol
		(lib_id "antmicroResistors0402:R_1k_0402")
		(at 107.95 96.52 180)
		(unit 1)
		(exclude_from_sim no)
		(in_bom yes)
		(on_board yes)
		(dnp no)
		(property "Reference" "R190"
			(at 102.87 95.25 0)
			(effects
				(font
					(size 1.27 1.27)
					(thickness 0.15)
				)
				(justify left)
			)
		)
		(property "Value" "R_1k_0402"
			(at 87.63 83.82 0)
			(effects
				(font
					(size 1.27 1.27)
					(thickness 0.15)
				)
				(justify left bottom)
				(hide yes)
			)
		)
		(property "Footprint" "antmicro-footprints:R_0402_1005Metric"
			(at 87.63 81.28 0)
			(effects
				(font
					(size 1.27 1.27)
					(thickness 0.15)
				)
				(justify left bottom)
				(hide yes)
			)
		)
		(property "Datasheet" "https://www.bourns.com/docs/product-datasheets/cr.pdf"
			(at 87.63 78.74 0)
			(effects
				(font
					(size 1.27 1.27)
					(thickness 0.15)
				)
				(justify left bottom)
				(hide yes)
			)
		)
		(property "Description" ""
			(at 107.95 96.52 0)
			(effects
				(font
					(size 1.27 1.27)
				)
				(hide yes)
			)
		)
		(property "MPN" "CR0402-FX-1001GLF"
			(at 87.63 76.2 0)
			(effects
				(font
					(size 1.27 1.27)
					(thickness 0.15)
				)
				(justify left bottom)
				(hide yes)
			)
		)
		(property "Manufacturer" "Bourns"
			(at 87.63 73.66 0)
			(effects
				(font
					(size 1.27 1.27)
					(thickness 0.15)
				)
				(justify left bottom)
				(hide yes)
			)
		)
		(property "License" "Apache-2.0"
			(at 87.63 71.12 0)
			(effects
				(font
					(size 1.27 1.27)
					(thickness 0.15)
				)
				(justify left bottom)
				(hide yes)
			)
		)
		(property "Author" "Antmicro"
			(at 87.63 68.58 0)
			(effects
				(font
					(size 1.27 1.27)
					(thickness 0.15)
				)
				(justify left bottom)
				(hide yes)
			)
		)
		(property "Val" "1k"
			(at 110.49 95.25 0)
			(effects
				(font
					(size 1.27 1.27)
					(thickness 0.15)
				)
				(justify left)
			)
		)
		(property "Tolerance" "1%"
			(at 87.63 86.36 0)
			(effects
				(font
					(size 1.27 1.27)
				)
				(justify left bottom)
				(hide yes)
			)
		)
		(property "Public" "False"
			(at 87.63 66.04 0)
			(effects
				(font
					(size 1.27 1.27)
				)
				(justify left bottom)
				(hide yes)
			)
		)
		(pin "2"
		)
		(pin "1"
		)
		(instances
			(project "com-express-7-baseboard"
				(path ""
					(reference "R190")
					(unit 1)
				)
			)
		)
	)
	(symbol
		(lib_id "antmicropower:GND")
		(at 87.63 109.22 0)
		(unit 1)
		(exclude_from_sim no)
		(in_bom yes)
		(on_board yes)
		(dnp no)
		(property "Reference" "#PWR0279"
			(at 96.52 111.76 0)
			(effects
				(font
					(size 1.27 1.27)
					(thickness 0.15)
				)
				(justify left bottom)
				(hide yes)
			)
		)
		(property "Value" "GND"
			(at 87.63 113.03 0)
			(effects
				(font
					(size 1.27 1.27)
					(thickness 0.15)
				)
			)
		)
		(property "Footprint" ""
			(at 96.52 116.84 0)
			(effects
				(font
					(size 1.27 1.27)
					(thickness 0.15)
				)
				(justify left bottom)
				(hide yes)
			)
		)
		(property "Datasheet" ""
			(at 96.52 121.92 0)
			(effects
				(font
					(size 1.27 1.27)
					(thickness 0.15)
				)
				(justify left bottom)
				(hide yes)
			)
		)
		(property "Description" ""
			(at 87.63 109.22 0)
			(effects
				(font
					(size 1.27 1.27)
				)
				(hide yes)
			)
		)
		(property "Author" "Antmicro"
			(at 96.52 116.84 0)
			(effects
				(font
					(size 1.27 1.27)
					(thickness 0.15)
				)
				(justify left bottom)
				(hide yes)
			)
		)
		(property "License" "Apache-2.0"
			(at 96.52 119.38 0)
			(effects
				(font
					(size 1.27 1.27)
					(thickness 0.15)
				)
				(justify left bottom)
				(hide yes)
			)
		)
		(pin "1"
		)
		(instances
			(project "com-express-7-baseboard"
				(path ""
					(reference "#PWR0279")
					(unit 1)
				)
			)
		)
	)
	(symbol
		(lib_id "antmicropower:GND")
		(at 54.61 109.22 0)
		(unit 1)
		(exclude_from_sim no)
		(in_bom yes)
		(on_board yes)
		(dnp no)
		(property "Reference" "#PWR0271"
			(at 63.5 111.76 0)
			(effects
				(font
					(size 1.27 1.27)
					(thickness 0.15)
				)
				(justify left bottom)
				(hide yes)
			)
		)
		(property "Value" "GND"
			(at 54.61 113.03 0)
			(effects
				(font
					(size 1.27 1.27)
					(thickness 0.15)
				)
			)
		)
		(property "Footprint" ""
			(at 63.5 116.84 0)
			(effects
				(font
					(size 1.27 1.27)
					(thickness 0.15)
				)
				(justify left bottom)
				(hide yes)
			)
		)
		(property "Datasheet" ""
			(at 63.5 121.92 0)
			(effects
				(font
					(size 1.27 1.27)
					(thickness 0.15)
				)
				(justify left bottom)
				(hide yes)
			)
		)
		(property "Description" ""
			(at 54.61 109.22 0)
			(effects
				(font
					(size 1.27 1.27)
				)
				(hide yes)
			)
		)
		(property "Author" "Antmicro"
			(at 63.5 116.84 0)
			(effects
				(font
					(size 1.27 1.27)
					(thickness 0.15)
				)
				(justify left bottom)
				(hide yes)
			)
		)
		(property "License" "Apache-2.0"
			(at 63.5 119.38 0)
			(effects
				(font
					(size 1.27 1.27)
					(thickness 0.15)
				)
				(justify left bottom)
				(hide yes)
			)
		)
		(pin "1"
		)
		(instances
			(project "com-express-7-baseboard"
				(path ""
					(reference "#PWR0271")
					(unit 1)
				)
			)
		)
	)
	(symbol
		(lib_id "antmicropower:+3V3")
		(at 74.93 199.39 0)
		(unit 1)
		(exclude_from_sim no)
		(in_bom yes)
		(on_board yes)
		(dnp no)
		(fields_autoplaced yes)
		(property "Reference" "#PWR0282"
			(at 90.17 199.39 0)
			(effects
				(font
					(size 1.27 1.27)
					(thickness 0.15)
				)
				(justify left bottom)
				(hide yes)
			)
		)
		(property "Value" "+3V3"
			(at 74.93 194.31 0)
			(effects
				(font
					(size 1.27 1.27)
					(thickness 0.15)
				)
			)
		)
		(property "Footprint" ""
			(at 90.17 207.01 0)
			(effects
				(font
					(size 1.27 1.27)
					(thickness 0.15)
				)
				(justify left bottom)
				(hide yes)
			)
		)
		(property "Datasheet" ""
			(at 90.17 209.55 0)
			(effects
				(font
					(size 1.27 1.27)
					(thickness 0.15)
				)
				(justify left bottom)
				(hide yes)
			)
		)
		(property "Description" ""
			(at 74.93 199.39 0)
			(effects
				(font
					(size 1.27 1.27)
				)
				(hide yes)
			)
		)
		(property "Author" "Antmicro"
			(at 90.17 201.93 0)
			(effects
				(font
					(size 1.27 1.27)
					(thickness 0.15)
				)
				(justify left bottom)
				(hide yes)
			)
		)
		(property "License" "Apache-2.0"
			(at 90.17 204.47 0)
			(effects
				(font
					(size 1.27 1.27)
					(thickness 0.15)
				)
				(justify left bottom)
				(hide yes)
			)
		)
		(pin "1"
		)
		(instances
			(project "com-express-7-baseboard"
				(path ""
					(reference "#PWR0282")
					(unit 1)
				)
			)
		)
	)
	(symbol
		(lib_id "antmicropower:GND")
		(at 67.31 109.22 0)
		(unit 1)
		(exclude_from_sim no)
		(in_bom yes)
		(on_board yes)
		(dnp no)
		(property "Reference" "#PWR0273"
			(at 76.2 111.76 0)
			(effects
				(font
					(size 1.27 1.27)
					(thickness 0.15)
				)
				(justify left bottom)
				(hide yes)
			)
		)
		(property "Value" "GND"
			(at 67.31 113.03 0)
			(effects
				(font
					(size 1.27 1.27)
					(thickness 0.15)
				)
			)
		)
		(property "Footprint" ""
			(at 76.2 116.84 0)
			(effects
				(font
					(size 1.27 1.27)
					(thickness 0.15)
				)
				(justify left bottom)
				(hide yes)
			)
		)
		(property "Datasheet" ""
			(at 76.2 121.92 0)
			(effects
				(font
					(size 1.27 1.27)
					(thickness 0.15)
				)
				(justify left bottom)
				(hide yes)
			)
		)
		(property "Description" ""
			(at 67.31 109.22 0)
			(effects
				(font
					(size 1.27 1.27)
				)
				(hide yes)
			)
		)
		(property "Author" "Antmicro"
			(at 76.2 116.84 0)
			(effects
				(font
					(size 1.27 1.27)
					(thickness 0.15)
				)
				(justify left bottom)
				(hide yes)
			)
		)
		(property "License" "Apache-2.0"
			(at 76.2 119.38 0)
			(effects
				(font
					(size 1.27 1.27)
					(thickness 0.15)
				)
				(justify left bottom)
				(hide yes)
			)
		)
		(pin "1"
		)
		(instances
			(project "com-express-7-baseboard"
				(path ""
					(reference "#PWR0273")
					(unit 1)
				)
			)
		)
	)
	(symbol
		(lib_id "antmicroResistors0402:R_0R_0402")
		(at 158.75 81.28 0)
		(unit 1)
		(exclude_from_sim no)
		(in_bom yes)
		(on_board yes)
		(dnp no)
		(property "Reference" "R198"
			(at 156.21 80.01 0)
			(effects
				(font
					(size 1.27 1.27)
					(thickness 0.15)
				)
			)
		)
		(property "Value" "R_0R_0402"
			(at 179.07 93.98 0)
			(effects
				(font
					(size 1.27 1.27)
					(thickness 0.15)
				)
				(justify left bottom)
				(hide yes)
			)
		)
		(property "Footprint" "antmicro-footprints:R_0402_1005Metric"
			(at 179.07 96.52 0)
			(effects
				(font
					(size 1.27 1.27)
					(thickness 0.15)
				)
				(justify left bottom)
				(hide yes)
			)
		)
		(property "Datasheet" "https://industrial.panasonic.com/cdbs/www-data/pdf/RDA0000/AOA0000C301.pdf"
			(at 179.07 99.06 0)
			(effects
				(font
					(size 1.27 1.27)
					(thickness 0.15)
				)
				(justify left bottom)
				(hide yes)
			)
		)
		(property "Description" ""
			(at 158.75 81.28 0)
			(effects
				(font
					(size 1.27 1.27)
				)
				(hide yes)
			)
		)
		(property "MPN" "ERJ2GE0R00X"
			(at 179.07 101.6 0)
			(effects
				(font
					(size 1.27 1.27)
					(thickness 0.15)
				)
				(justify left bottom)
				(hide yes)
			)
		)
		(property "Manufacturer" "Panasonic"
			(at 179.07 104.14 0)
			(effects
				(font
					(size 1.27 1.27)
					(thickness 0.15)
				)
				(justify left bottom)
				(hide yes)
			)
		)
		(property "License" "Apache-2.0"
			(at 179.07 106.68 0)
			(effects
				(font
					(size 1.27 1.27)
					(thickness 0.15)
				)
				(justify left bottom)
				(hide yes)
			)
		)
		(property "Author" "Antmicro"
			(at 179.07 109.22 0)
			(effects
				(font
					(size 1.27 1.27)
					(thickness 0.15)
				)
				(justify left bottom)
				(hide yes)
			)
		)
		(property "Val" "0R"
			(at 165.1 80.01 0)
			(effects
				(font
					(size 1.27 1.27)
					(thickness 0.15)
				)
			)
		)
		(property "Tolerance" "~"
			(at 179.07 91.44 0)
			(effects
				(font
					(size 1.27 1.27)
				)
				(justify left bottom)
				(hide yes)
			)
		)
		(property "Current" "1A"
			(at 179.07 111.76 0)
			(effects
				(font
					(size 1.27 1.27)
					(thickness 0.15)
				)
				(justify left bottom)
				(hide yes)
			)
		)
		(property "Public" "False"
			(at 179.07 111.76 0)
			(effects
				(font
					(size 1.27 1.27)
				)
				(justify left bottom)
				(hide yes)
			)
		)
		(pin "1"
		)
		(pin "2"
		)
		(instances
			(project "com-express-7-baseboard"
				(path ""
					(reference "R198")
					(unit 1)
				)
			)
		)
	)
	(symbol
		(lib_id "antmicroResistors0402:R_0R_0402")
		(at 158.75 76.2 0)
		(unit 1)
		(exclude_from_sim no)
		(in_bom yes)
		(on_board yes)
		(dnp no)
		(property "Reference" "R197"
			(at 156.21 74.93 0)
			(effects
				(font
					(size 1.27 1.27)
					(thickness 0.15)
				)
			)
		)
		(property "Value" "R_0R_0402"
			(at 179.07 88.9 0)
			(effects
				(font
					(size 1.27 1.27)
					(thickness 0.15)
				)
				(justify left bottom)
				(hide yes)
			)
		)
		(property "Footprint" "antmicro-footprints:R_0402_1005Metric"
			(at 179.07 91.44 0)
			(effects
				(font
					(size 1.27 1.27)
					(thickness 0.15)
				)
				(justify left bottom)
				(hide yes)
			)
		)
		(property "Datasheet" "https://industrial.panasonic.com/cdbs/www-data/pdf/RDA0000/AOA0000C301.pdf"
			(at 179.07 93.98 0)
			(effects
				(font
					(size 1.27 1.27)
					(thickness 0.15)
				)
				(justify left bottom)
				(hide yes)
			)
		)
		(property "Description" ""
			(at 158.75 76.2 0)
			(effects
				(font
					(size 1.27 1.27)
				)
				(hide yes)
			)
		)
		(property "MPN" "ERJ2GE0R00X"
			(at 179.07 96.52 0)
			(effects
				(font
					(size 1.27 1.27)
					(thickness 0.15)
				)
				(justify left bottom)
				(hide yes)
			)
		)
		(property "Manufacturer" "Panasonic"
			(at 179.07 99.06 0)
			(effects
				(font
					(size 1.27 1.27)
					(thickness 0.15)
				)
				(justify left bottom)
				(hide yes)
			)
		)
		(property "License" "Apache-2.0"
			(at 179.07 101.6 0)
			(effects
				(font
					(size 1.27 1.27)
					(thickness 0.15)
				)
				(justify left bottom)
				(hide yes)
			)
		)
		(property "Author" "Antmicro"
			(at 179.07 104.14 0)
			(effects
				(font
					(size 1.27 1.27)
					(thickness 0.15)
				)
				(justify left bottom)
				(hide yes)
			)
		)
		(property "Val" "0R"
			(at 165.1 74.93 0)
			(effects
				(font
					(size 1.27 1.27)
					(thickness 0.15)
				)
			)
		)
		(property "Tolerance" "~"
			(at 179.07 86.36 0)
			(effects
				(font
					(size 1.27 1.27)
				)
				(justify left bottom)
				(hide yes)
			)
		)
		(property "Current" "1A"
			(at 179.07 106.68 0)
			(effects
				(font
					(size 1.27 1.27)
					(thickness 0.15)
				)
				(justify left bottom)
				(hide yes)
			)
		)
		(property "Public" "False"
			(at 179.07 106.68 0)
			(effects
				(font
					(size 1.27 1.27)
				)
				(justify left bottom)
				(hide yes)
			)
		)
		(pin "1"
		)
		(pin "2"
		)
		(instances
			(project "com-express-7-baseboard"
				(path ""
					(reference "R197")
					(unit 1)
				)
			)
		)
	)
	(symbol
		(lib_id "antmicroCapacitors0402:C_100n_0402")
		(at 74.93 207.01 90)
		(unit 1)
		(exclude_from_sim no)
		(in_bom yes)
		(on_board yes)
		(dnp no)
		(fields_autoplaced yes)
		(property "Reference" "C109"
			(at 77.47 203.1936 90)
			(effects
				(font
					(size 1.27 1.27)
					(thickness 0.15)
				)
				(justify right)
			)
		)
		(property "Value" "C_100n_0402"
			(at 85.09 186.69 0)
			(effects
				(font
					(size 1.27 1.27)
					(thickness 0.15)
				)
				(justify left bottom)
				(hide yes)
			)
		)
		(property "Footprint" "antmicro-footprints:C_0402_1005Metric"
			(at 87.63 186.69 0)
			(effects
				(font
					(size 1.27 1.27)
					(thickness 0.15)
				)
				(justify left bottom)
				(hide yes)
			)
		)
		(property "Datasheet" "https://www.murata.com/products/productdetail?partno=GRM155R61H104KE14%23"
			(at 90.17 186.69 0)
			(effects
				(font
					(size 1.27 1.27)
					(thickness 0.15)
				)
				(justify left bottom)
				(hide yes)
			)
		)
		(property "Description" ""
			(at 74.93 207.01 0)
			(effects
				(font
					(size 1.27 1.27)
				)
				(hide yes)
			)
		)
		(property "MPN" "GRM155R61H104KE14D"
			(at 92.71 186.69 0)
			(effects
				(font
					(size 1.27 1.27)
					(thickness 0.15)
				)
				(justify left bottom)
				(hide yes)
			)
		)
		(property "Manufacturer" "Murata"
			(at 95.25 186.69 0)
			(effects
				(font
					(size 1.27 1.27)
					(thickness 0.15)
				)
				(justify left bottom)
				(hide yes)
			)
		)
		(property "License" "Apache-2.0"
			(at 97.79 186.69 0)
			(effects
				(font
					(size 1.27 1.27)
					(thickness 0.15)
				)
				(justify left bottom)
				(hide yes)
			)
		)
		(property "Author" "Antmicro"
			(at 100.33 186.69 0)
			(effects
				(font
					(size 1.27 1.27)
					(thickness 0.15)
				)
				(justify left bottom)
				(hide yes)
			)
		)
		(property "Val" "100n"
			(at 77.47 205.7336 90)
			(effects
				(font
					(size 1.27 1.27)
					(thickness 0.15)
				)
				(justify right)
			)
		)
		(property "Voltage" "50V"
			(at 102.87 186.69 0)
			(effects
				(font
					(size 1.27 1.27)
				)
				(justify left bottom)
				(hide yes)
			)
		)
		(property "Dielectric" "X5R"
			(at 105.41 186.69 0)
			(effects
				(font
					(size 1.27 1.27)
				)
				(justify left bottom)
				(hide yes)
			)
		)
		(property "Public" "False"
			(at 107.95 186.69 0)
			(effects
				(font
					(size 1.27 1.27)
				)
				(justify left bottom)
				(hide yes)
			)
		)
		(pin "1"
		)
		(pin "2"
		)
		(instances
			(project "com-express-7-baseboard"
				(path ""
					(reference "C109")
					(unit 1)
				)
			)
		)
	)
	(symbol
		(lib_id "antmicroTestPoints:TP_0.75mm_SMD")
		(at 107.95 104.14 180)
		(unit 1)
		(exclude_from_sim no)
		(in_bom no)
		(on_board yes)
		(dnp no)
		(property "Reference" "TP44"
			(at 101.6 104.14 0)
			(effects
				(font
					(size 1.27 1.27)
					(thickness 0.15)
				)
			)
		)
		(property "Value" "TP_0.75mm_SMD"
			(at 97.155 100.33 0)
			(effects
				(font
					(size 1.27 1.27)
					(thickness 0.15)
				)
				(justify left bottom)
				(hide yes)
			)
		)
		(property "Footprint" "antmicro-footprints:TP_SMD_0.75mm"
			(at 97.155 97.79 0)
			(effects
				(font
					(size 1.27 1.27)
					(thickness 0.15)
				)
				(justify left bottom)
				(hide yes)
			)
		)
		(property "Datasheet" ""
			(at 90.17 91.44 0)
			(effects
				(font
					(size 1.27 1.27)
					(thickness 0.15)
				)
				(justify left bottom)
				(hide yes)
			)
		)
		(property "Description" ""
			(at 107.95 104.14 0)
			(effects
				(font
					(size 1.27 1.27)
				)
				(hide yes)
			)
		)
		(property "MPN" ""
			(at 97.155 92.71 0)
			(effects
				(font
					(size 1.27 1.27)
					(thickness 0.15)
				)
				(justify left bottom)
				(hide yes)
			)
		)
		(property "Manufacturer" ""
			(at 97.155 97.79 0)
			(effects
				(font
					(size 1.27 1.27)
					(thickness 0.15)
				)
				(justify left bottom)
				(hide yes)
			)
		)
		(property "Author" "Antmicro"
			(at 97.155 95.25 0)
			(effects
				(font
					(size 1.27 1.27)
					(thickness 0.15)
				)
				(justify left bottom)
				(hide yes)
			)
		)
		(property "License" "Apache-2.0"
			(at 97.155 92.71 0)
			(effects
				(font
					(size 1.27 1.27)
					(thickness 0.15)
				)
				(justify left bottom)
				(hide yes)
			)
		)
		(property "Public" "False"
			(at 97.79 90.17 0)
			(effects
				(font
					(size 1.27 1.27)
				)
				(justify left bottom)
				(hide yes)
			)
		)
		(pin "1"
		)
		(instances
			(project "com-express-7-baseboard"
				(path ""
					(reference "TP44")
					(unit 1)
				)
			)
		)
	)
	(symbol
		(lib_id "antmicropower:GND")
		(at 100.33 57.15 0)
		(unit 1)
		(exclude_from_sim no)
		(in_bom yes)
		(on_board yes)
		(dnp no)
		(property "Reference" "#PWR0430"
			(at 100.33 63.5 0)
			(effects
				(font
					(size 1.27 1.27)
				)
				(justify left bottom)
				(hide yes)
			)
		)
		(property "Value" "GND"
			(at 98.425 62.23 0)
			(effects
				(font
					(size 1.27 1.27)
				)
				(justify left bottom)
			)
		)
		(property "Footprint" ""
			(at 100.33 57.15 0)
			(effects
				(font
					(size 1.27 1.27)
				)
				(justify left bottom)
				(hide yes)
			)
		)
		(property "Datasheet" ""
			(at 100.33 57.15 0)
			(effects
				(font
					(size 1.27 1.27)
				)
				(justify left bottom)
				(hide yes)
			)
		)
		(property "Description" ""
			(at 100.33 57.15 0)
			(effects
				(font
					(size 1.27 1.27)
				)
				(hide yes)
			)
		)
		(property "Author" "Antmicro"
			(at 109.22 64.77 0)
			(effects
				(font
					(size 1.27 1.27)
					(thickness 0.15)
				)
				(justify left bottom)
				(hide yes)
			)
		)
		(property "License" "Apache-2.0"
			(at 109.22 67.31 0)
			(effects
				(font
					(size 1.27 1.27)
					(thickness 0.15)
				)
				(justify left bottom)
				(hide yes)
			)
		)
		(pin "1"
		)
		(instances
			(project "com-express-7-baseboard"
				(path ""
					(reference "#PWR0430")
					(unit 1)
				)
			)
		)
	)
	(symbol
		(lib_id "antmicroResistors0402:R_0R_0402")
		(at 158.75 66.04 0)
		(unit 1)
		(exclude_from_sim no)
		(in_bom yes)
		(on_board yes)
		(dnp no)
		(property "Reference" "R194"
			(at 156.21 64.77 0)
			(effects
				(font
					(size 1.27 1.27)
					(thickness 0.15)
				)
			)
		)
		(property "Value" "R_0R_0402"
			(at 179.07 78.74 0)
			(effects
				(font
					(size 1.27 1.27)
					(thickness 0.15)
				)
				(justify left bottom)
				(hide yes)
			)
		)
		(property "Footprint" "antmicro-footprints:R_0402_1005Metric"
			(at 179.07 81.28 0)
			(effects
				(font
					(size 1.27 1.27)
					(thickness 0.15)
				)
				(justify left bottom)
				(hide yes)
			)
		)
		(property "Datasheet" "https://industrial.panasonic.com/cdbs/www-data/pdf/RDA0000/AOA0000C301.pdf"
			(at 179.07 83.82 0)
			(effects
				(font
					(size 1.27 1.27)
					(thickness 0.15)
				)
				(justify left bottom)
				(hide yes)
			)
		)
		(property "Description" ""
			(at 158.75 66.04 0)
			(effects
				(font
					(size 1.27 1.27)
				)
				(hide yes)
			)
		)
		(property "MPN" "ERJ2GE0R00X"
			(at 179.07 86.36 0)
			(effects
				(font
					(size 1.27 1.27)
					(thickness 0.15)
				)
				(justify left bottom)
				(hide yes)
			)
		)
		(property "Manufacturer" "Panasonic"
			(at 179.07 88.9 0)
			(effects
				(font
					(size 1.27 1.27)
					(thickness 0.15)
				)
				(justify left bottom)
				(hide yes)
			)
		)
		(property "License" "Apache-2.0"
			(at 179.07 91.44 0)
			(effects
				(font
					(size 1.27 1.27)
					(thickness 0.15)
				)
				(justify left bottom)
				(hide yes)
			)
		)
		(property "Author" "Antmicro"
			(at 179.07 93.98 0)
			(effects
				(font
					(size 1.27 1.27)
					(thickness 0.15)
				)
				(justify left bottom)
				(hide yes)
			)
		)
		(property "Val" "0R"
			(at 165.1 64.77 0)
			(effects
				(font
					(size 1.27 1.27)
					(thickness 0.15)
				)
			)
		)
		(property "Tolerance" "~"
			(at 179.07 76.2 0)
			(effects
				(font
					(size 1.27 1.27)
				)
				(justify left bottom)
				(hide yes)
			)
		)
		(property "Current" "1A"
			(at 179.07 96.52 0)
			(effects
				(font
					(size 1.27 1.27)
					(thickness 0.15)
				)
				(justify left bottom)
				(hide yes)
			)
		)
		(property "Public" "False"
			(at 179.07 96.52 0)
			(effects
				(font
					(size 1.27 1.27)
				)
				(justify left bottom)
				(hide yes)
			)
		)
		(pin "1"
		)
		(pin "2"
		)
		(instances
			(project "com-express-7-baseboard"
				(path ""
					(reference "R194")
					(unit 1)
				)
			)
		)
	)
	(symbol
		(lib_id "antmicropower:GND")
		(at 143.51 115.57 0)
		(unit 1)
		(exclude_from_sim no)
		(in_bom yes)
		(on_board yes)
		(dnp no)
		(property "Reference" "#PWR0287"
			(at 152.4 118.11 0)
			(effects
				(font
					(size 1.27 1.27)
					(thickness 0.15)
				)
				(justify left bottom)
				(hide yes)
			)
		)
		(property "Value" "GND"
			(at 143.51 119.38 0)
			(effects
				(font
					(size 1.27 1.27)
					(thickness 0.15)
				)
			)
		)
		(property "Footprint" ""
			(at 152.4 123.19 0)
			(effects
				(font
					(size 1.27 1.27)
					(thickness 0.15)
				)
				(justify left bottom)
				(hide yes)
			)
		)
		(property "Datasheet" ""
			(at 152.4 128.27 0)
			(effects
				(font
					(size 1.27 1.27)
					(thickness 0.15)
				)
				(justify left bottom)
				(hide yes)
			)
		)
		(property "Description" ""
			(at 143.51 115.57 0)
			(effects
				(font
					(size 1.27 1.27)
				)
				(hide yes)
			)
		)
		(property "Author" "Antmicro"
			(at 152.4 123.19 0)
			(effects
				(font
					(size 1.27 1.27)
					(thickness 0.15)
				)
				(justify left bottom)
				(hide yes)
			)
		)
		(property "License" "Apache-2.0"
			(at 152.4 125.73 0)
			(effects
				(font
					(size 1.27 1.27)
					(thickness 0.15)
				)
				(justify left bottom)
				(hide yes)
			)
		)
		(pin "1"
		)
		(instances
			(project "com-express-7-baseboard"
				(path ""
					(reference "#PWR0287")
					(unit 1)
				)
			)
		)
	)
	(symbol
		(lib_id "antmicroCapacitors0402:C_100n_0402")
		(at 63.5 57.15 90)
		(unit 1)
		(exclude_from_sim no)
		(in_bom yes)
		(on_board yes)
		(dnp no)
		(fields_autoplaced yes)
		(property "Reference" "C108"
			(at 66.04 53.3336 90)
			(effects
				(font
					(size 1.27 1.27)
					(thickness 0.15)
				)
				(justify right)
			)
		)
		(property "Value" "C_100n_0402"
			(at 73.66 36.83 0)
			(effects
				(font
					(size 1.27 1.27)
					(thickness 0.15)
				)
				(justify left bottom)
				(hide yes)
			)
		)
		(property "Footprint" "antmicro-footprints:C_0402_1005Metric"
			(at 76.2 36.83 0)
			(effects
				(font
					(size 1.27 1.27)
					(thickness 0.15)
				)
				(justify left bottom)
				(hide yes)
			)
		)
		(property "Datasheet" "https://www.murata.com/products/productdetail?partno=GRM155R61H104KE14%23"
			(at 78.74 36.83 0)
			(effects
				(font
					(size 1.27 1.27)
					(thickness 0.15)
				)
				(justify left bottom)
				(hide yes)
			)
		)
		(property "Description" ""
			(at 63.5 57.15 0)
			(effects
				(font
					(size 1.27 1.27)
				)
				(hide yes)
			)
		)
		(property "MPN" "GRM155R61H104KE14D"
			(at 81.28 36.83 0)
			(effects
				(font
					(size 1.27 1.27)
					(thickness 0.15)
				)
				(justify left bottom)
				(hide yes)
			)
		)
		(property "Manufacturer" "Murata"
			(at 83.82 36.83 0)
			(effects
				(font
					(size 1.27 1.27)
					(thickness 0.15)
				)
				(justify left bottom)
				(hide yes)
			)
		)
		(property "License" "Apache-2.0"
			(at 86.36 36.83 0)
			(effects
				(font
					(size 1.27 1.27)
					(thickness 0.15)
				)
				(justify left bottom)
				(hide yes)
			)
		)
		(property "Author" "Antmicro"
			(at 88.9 36.83 0)
			(effects
				(font
					(size 1.27 1.27)
					(thickness 0.15)
				)
				(justify left bottom)
				(hide yes)
			)
		)
		(property "Val" "100n"
			(at 66.04 55.8736 90)
			(effects
				(font
					(size 1.27 1.27)
					(thickness 0.15)
				)
				(justify right)
			)
		)
		(property "Voltage" "50V"
			(at 91.44 36.83 0)
			(effects
				(font
					(size 1.27 1.27)
				)
				(justify left bottom)
				(hide yes)
			)
		)
		(property "Dielectric" "X5R"
			(at 93.98 36.83 0)
			(effects
				(font
					(size 1.27 1.27)
				)
				(justify left bottom)
				(hide yes)
			)
		)
		(property "Public" "False"
			(at 96.52 36.83 0)
			(effects
				(font
					(size 1.27 1.27)
				)
				(justify left bottom)
				(hide yes)
			)
		)
		(pin "1"
		)
		(pin "2"
		)
		(instances
			(project "com-express-7-baseboard"
				(path ""
					(reference "C108")
					(unit 1)
				)
			)
		)
	)
	(symbol
		(lib_id "antmicroResistors0402:R_0R_0402")
		(at 158.75 60.96 0)
		(unit 1)
		(exclude_from_sim no)
		(in_bom yes)
		(on_board yes)
		(dnp no)
		(property "Reference" "R193"
			(at 156.21 59.69 0)
			(effects
				(font
					(size 1.27 1.27)
					(thickness 0.15)
				)
			)
		)
		(property "Value" "R_0R_0402"
			(at 179.07 73.66 0)
			(effects
				(font
					(size 1.27 1.27)
					(thickness 0.15)
				)
				(justify left bottom)
				(hide yes)
			)
		)
		(property "Footprint" "antmicro-footprints:R_0402_1005Metric"
			(at 179.07 76.2 0)
			(effects
				(font
					(size 1.27 1.27)
					(thickness 0.15)
				)
				(justify left bottom)
				(hide yes)
			)
		)
		(property "Datasheet" "https://industrial.panasonic.com/cdbs/www-data/pdf/RDA0000/AOA0000C301.pdf"
			(at 179.07 78.74 0)
			(effects
				(font
					(size 1.27 1.27)
					(thickness 0.15)
				)
				(justify left bottom)
				(hide yes)
			)
		)
		(property "Description" ""
			(at 158.75 60.96 0)
			(effects
				(font
					(size 1.27 1.27)
				)
				(hide yes)
			)
		)
		(property "MPN" "ERJ2GE0R00X"
			(at 179.07 81.28 0)
			(effects
				(font
					(size 1.27 1.27)
					(thickness 0.15)
				)
				(justify left bottom)
				(hide yes)
			)
		)
		(property "Manufacturer" "Panasonic"
			(at 179.07 83.82 0)
			(effects
				(font
					(size 1.27 1.27)
					(thickness 0.15)
				)
				(justify left bottom)
				(hide yes)
			)
		)
		(property "License" "Apache-2.0"
			(at 179.07 86.36 0)
			(effects
				(font
					(size 1.27 1.27)
					(thickness 0.15)
				)
				(justify left bottom)
				(hide yes)
			)
		)
		(property "Author" "Antmicro"
			(at 179.07 88.9 0)
			(effects
				(font
					(size 1.27 1.27)
					(thickness 0.15)
				)
				(justify left bottom)
				(hide yes)
			)
		)
		(property "Val" "0R"
			(at 165.1 59.69 0)
			(effects
				(font
					(size 1.27 1.27)
					(thickness 0.15)
				)
			)
		)
		(property "Tolerance" "~"
			(at 179.07 71.12 0)
			(effects
				(font
					(size 1.27 1.27)
				)
				(justify left bottom)
				(hide yes)
			)
		)
		(property "Current" "1A"
			(at 179.07 91.44 0)
			(effects
				(font
					(size 1.27 1.27)
					(thickness 0.15)
				)
				(justify left bottom)
				(hide yes)
			)
		)
		(property "Public" "False"
			(at 179.07 91.44 0)
			(effects
				(font
					(size 1.27 1.27)
				)
				(justify left bottom)
				(hide yes)
			)
		)
		(pin "1"
		)
		(pin "2"
		)
		(instances
			(project "com-express-7-baseboard"
				(path ""
					(reference "R193")
					(unit 1)
				)
			)
		)
	)
	(symbol
		(lib_id "antmicroResistors0402:R_1k_0402")
		(at 87.63 102.87 90)
		(mirror x)
		(unit 1)
		(exclude_from_sim no)
		(in_bom yes)
		(on_board yes)
		(dnp yes)
		(fields_autoplaced yes)
		(property "Reference" "R188"
			(at 90.17 102.87 90)
			(effects
				(font
					(size 1.27 1.27)
					(thickness 0.15)
				)
				(justify right)
			)
		)
		(property "Value" "R_1k_0402"
			(at 100.33 123.19 0)
			(effects
				(font
					(size 1.27 1.27)
					(thickness 0.15)
				)
				(justify left bottom)
				(hide yes)
			)
		)
		(property "Footprint" "antmicro-footprints:R_0402_1005Metric"
			(at 102.87 123.19 0)
			(effects
				(font
					(size 1.27 1.27)
					(thickness 0.15)
				)
				(justify left bottom)
				(hide yes)
			)
		)
		(property "Datasheet" "https://www.bourns.com/docs/product-datasheets/cr.pdf"
			(at 105.41 123.19 0)
			(effects
				(font
					(size 1.27 1.27)
					(thickness 0.15)
				)
				(justify left bottom)
				(hide yes)
			)
		)
		(property "Description" ""
			(at 87.63 102.87 0)
			(effects
				(font
					(size 1.27 1.27)
				)
				(hide yes)
			)
		)
		(property "MPN" "CR0402-FX-1001GLF"
			(at 107.95 123.19 0)
			(effects
				(font
					(size 1.27 1.27)
					(thickness 0.15)
				)
				(justify left bottom)
				(hide yes)
			)
		)
		(property "Manufacturer" "Bourns"
			(at 110.49 123.19 0)
			(effects
				(font
					(size 1.27 1.27)
					(thickness 0.15)
				)
				(justify left bottom)
				(hide yes)
			)
		)
		(property "License" "Apache-2.0"
			(at 113.03 123.19 0)
			(effects
				(font
					(size 1.27 1.27)
					(thickness 0.15)
				)
				(justify left bottom)
				(hide yes)
			)
		)
		(property "Author" "Antmicro"
			(at 115.57 123.19 0)
			(effects
				(font
					(size 1.27 1.27)
					(thickness 0.15)
				)
				(justify left bottom)
				(hide yes)
			)
		)
		(property "Val" "1k"
			(at 90.17 105.41 90)
			(effects
				(font
					(size 1.27 1.27)
					(thickness 0.15)
				)
				(justify right)
			)
		)
		(property "Tolerance" "1%"
			(at 97.79 123.19 0)
			(effects
				(font
					(size 1.27 1.27)
				)
				(justify left bottom)
				(hide yes)
			)
		)
		(property "Public" "False"
			(at 118.11 123.19 0)
			(effects
				(font
					(size 1.27 1.27)
				)
				(justify left bottom)
				(hide yes)
			)
		)
		(pin "2"
		)
		(pin "1"
		)
		(instances
			(project "com-express-7-baseboard"
				(path ""
					(reference "R188")
					(unit 1)
				)
			)
		)
	)
	(symbol
		(lib_id "antmicroLogicGatesandInverters:74AUP2G132")
		(at 124.46 203.2 0)
		(unit 1)
		(exclude_from_sim no)
		(in_bom yes)
		(on_board yes)
		(dnp no)
		(fields_autoplaced yes)
		(property "Reference" "U38"
			(at 133.35 196.85 0)
			(effects
				(font
					(size 1.27 1.27)
					(thickness 0.15)
				)
			)
		)
		(property "Value" "74AUP2G132"
			(at 170.18 213.36 0)
			(effects
				(font
					(size 1.27 1.27)
					(thickness 0.15)
				)
				(justify left bottom)
				(hide yes)
			)
		)
		(property "Footprint" "antmicro-footprints:VSSOP-8_2.3x2mm_P0.5mm"
			(at 170.18 215.9 0)
			(effects
				(font
					(size 1.27 1.27)
					(thickness 0.15)
				)
				(justify left bottom)
				(hide yes)
			)
		)
		(property "Datasheet" "https://assets.nexperia.com/documents/data-sheet/74AUP2G132.pdf"
			(at 170.18 218.44 0)
			(effects
				(font
					(size 1.27 1.27)
					(thickness 0.15)
				)
				(justify left bottom)
				(hide yes)
			)
		)
		(property "Description" ""
			(at 124.46 203.2 0)
			(effects
				(font
					(size 1.27 1.27)
				)
				(hide yes)
			)
		)
		(property "Manufacturer" "Nexperia"
			(at 170.18 220.98 0)
			(effects
				(font
					(size 1.27 1.27)
					(thickness 0.15)
				)
				(justify left bottom)
				(hide yes)
			)
		)
		(property "MPN" "74AUP2G132"
			(at 133.35 199.39 0)
			(effects
				(font
					(size 1.27 1.27)
					(thickness 0.15)
				)
			)
		)
		(property "Author" "Antmicro"
			(at 170.18 223.52 0)
			(effects
				(font
					(size 1.27 1.27)
					(thickness 0.15)
				)
				(justify left bottom)
				(hide yes)
			)
		)
		(property "License" "Apache-2.0"
			(at 170.18 226.06 0)
			(effects
				(font
					(size 1.27 1.27)
					(thickness 0.15)
				)
				(justify left bottom)
				(hide yes)
			)
		)
		(pin "2"
		)
		(pin "4"
		)
		(pin "7"
		)
		(pin "8"
		)
		(pin "3"
		)
		(pin "6"
		)
		(pin "1"
		)
		(pin "5"
		)
		(instances
			(project "com-express-7-baseboard"
				(path ""
					(reference "U38")
					(unit 1)
				)
			)
		)
	)
	(symbol
		(lib_id "antmicroCapacitors0402:C_100n_0402")
		(at 54.61 57.15 90)
		(unit 1)
		(exclude_from_sim no)
		(in_bom yes)
		(on_board yes)
		(dnp no)
		(fields_autoplaced yes)
		(property "Reference" "C107"
			(at 57.15 53.3336 90)
			(effects
				(font
					(size 1.27 1.27)
					(thickness 0.15)
				)
				(justify right)
			)
		)
		(property "Value" "C_100n_0402"
			(at 64.77 36.83 0)
			(effects
				(font
					(size 1.27 1.27)
					(thickness 0.15)
				)
				(justify left bottom)
				(hide yes)
			)
		)
		(property "Footprint" "antmicro-footprints:C_0402_1005Metric"
			(at 67.31 36.83 0)
			(effects
				(font
					(size 1.27 1.27)
					(thickness 0.15)
				)
				(justify left bottom)
				(hide yes)
			)
		)
		(property "Datasheet" "https://www.murata.com/products/productdetail?partno=GRM155R61H104KE14%23"
			(at 69.85 36.83 0)
			(effects
				(font
					(size 1.27 1.27)
					(thickness 0.15)
				)
				(justify left bottom)
				(hide yes)
			)
		)
		(property "Description" ""
			(at 54.61 57.15 0)
			(effects
				(font
					(size 1.27 1.27)
				)
				(hide yes)
			)
		)
		(property "MPN" "GRM155R61H104KE14D"
			(at 72.39 36.83 0)
			(effects
				(font
					(size 1.27 1.27)
					(thickness 0.15)
				)
				(justify left bottom)
				(hide yes)
			)
		)
		(property "Manufacturer" "Murata"
			(at 74.93 36.83 0)
			(effects
				(font
					(size 1.27 1.27)
					(thickness 0.15)
				)
				(justify left bottom)
				(hide yes)
			)
		)
		(property "License" "Apache-2.0"
			(at 77.47 36.83 0)
			(effects
				(font
					(size 1.27 1.27)
					(thickness 0.15)
				)
				(justify left bottom)
				(hide yes)
			)
		)
		(property "Author" "Antmicro"
			(at 80.01 36.83 0)
			(effects
				(font
					(size 1.27 1.27)
					(thickness 0.15)
				)
				(justify left bottom)
				(hide yes)
			)
		)
		(property "Val" "100n"
			(at 57.15 55.8736 90)
			(effects
				(font
					(size 1.27 1.27)
					(thickness 0.15)
				)
				(justify right)
			)
		)
		(property "Voltage" "50V"
			(at 82.55 36.83 0)
			(effects
				(font
					(size 1.27 1.27)
				)
				(justify left bottom)
				(hide yes)
			)
		)
		(property "Dielectric" "X5R"
			(at 85.09 36.83 0)
			(effects
				(font
					(size 1.27 1.27)
				)
				(justify left bottom)
				(hide yes)
			)
		)
		(property "Public" "False"
			(at 87.63 36.83 0)
			(effects
				(font
					(size 1.27 1.27)
				)
				(justify left bottom)
				(hide yes)
			)
		)
		(pin "1"
		)
		(pin "2"
		)
		(instances
			(project "com-express-7-baseboard"
				(path ""
					(reference "C107")
					(unit 1)
				)
			)
		)
	)
	(symbol
		(lib_id "antmicropower:GND")
		(at 123.19 217.17 0)
		(unit 1)
		(exclude_from_sim no)
		(in_bom yes)
		(on_board yes)
		(dnp no)
		(property "Reference" "#PWR0288"
			(at 132.08 219.71 0)
			(effects
				(font
					(size 1.27 1.27)
					(thickness 0.15)
				)
				(justify left bottom)
				(hide yes)
			)
		)
		(property "Value" "GND"
			(at 123.19 220.98 0)
			(effects
				(font
					(size 1.27 1.27)
					(thickness 0.15)
				)
			)
		)
		(property "Footprint" ""
			(at 132.08 224.79 0)
			(effects
				(font
					(size 1.27 1.27)
					(thickness 0.15)
				)
				(justify left bottom)
				(hide yes)
			)
		)
		(property "Datasheet" ""
			(at 132.08 229.87 0)
			(effects
				(font
					(size 1.27 1.27)
					(thickness 0.15)
				)
				(justify left bottom)
				(hide yes)
			)
		)
		(property "Description" ""
			(at 123.19 217.17 0)
			(effects
				(font
					(size 1.27 1.27)
				)
				(hide yes)
			)
		)
		(property "Author" "Antmicro"
			(at 132.08 224.79 0)
			(effects
				(font
					(size 1.27 1.27)
					(thickness 0.15)
				)
				(justify left bottom)
				(hide yes)
			)
		)
		(property "License" "Apache-2.0"
			(at 132.08 227.33 0)
			(effects
				(font
					(size 1.27 1.27)
					(thickness 0.15)
				)
				(justify left bottom)
				(hide yes)
			)
		)
		(pin "1"
		)
		(instances
			(project "com-express-7-baseboard"
				(path ""
					(reference "#PWR0288")
					(unit 1)
				)
			)
		)
	)
	(symbol
		(lib_id "antmicroResistors0402:R_1k_0402")
		(at 60.96 102.87 270)
		(unit 1)
		(exclude_from_sim no)
		(in_bom yes)
		(on_board yes)
		(dnp no)
		(property "Reference" "R183"
			(at 59.69 102.87 90)
			(effects
				(font
					(size 1.27 1.27)
					(thickness 0.15)
				)
				(justify right)
			)
		)
		(property "Value" "R_1k_0402"
			(at 48.26 123.19 0)
			(effects
				(font
					(size 1.27 1.27)
					(thickness 0.15)
				)
				(justify left bottom)
				(hide yes)
			)
		)
		(property "Footprint" "antmicro-footprints:R_0402_1005Metric"
			(at 45.72 123.19 0)
			(effects
				(font
					(size 1.27 1.27)
					(thickness 0.15)
				)
				(justify left bottom)
				(hide yes)
			)
		)
		(property "Datasheet" "https://www.bourns.com/docs/product-datasheets/cr.pdf"
			(at 43.18 123.19 0)
			(effects
				(font
					(size 1.27 1.27)
					(thickness 0.15)
				)
				(justify left bottom)
				(hide yes)
			)
		)
		(property "Description" ""
			(at 60.96 102.87 0)
			(effects
				(font
					(size 1.27 1.27)
				)
				(hide yes)
			)
		)
		(property "MPN" "CR0402-FX-1001GLF"
			(at 40.64 123.19 0)
			(effects
				(font
					(size 1.27 1.27)
					(thickness 0.15)
				)
				(justify left bottom)
				(hide yes)
			)
		)
		(property "Manufacturer" "Bourns"
			(at 38.1 123.19 0)
			(effects
				(font
					(size 1.27 1.27)
					(thickness 0.15)
				)
				(justify left bottom)
				(hide yes)
			)
		)
		(property "License" "Apache-2.0"
			(at 35.56 123.19 0)
			(effects
				(font
					(size 1.27 1.27)
					(thickness 0.15)
				)
				(justify left bottom)
				(hide yes)
			)
		)
		(property "Author" "Antmicro"
			(at 33.02 123.19 0)
			(effects
				(font
					(size 1.27 1.27)
					(thickness 0.15)
				)
				(justify left bottom)
				(hide yes)
			)
		)
		(property "Val" "1k"
			(at 59.69 105.41 90)
			(effects
				(font
					(size 1.27 1.27)
					(thickness 0.15)
				)
				(justify right)
			)
		)
		(property "Tolerance" "1%"
			(at 50.8 123.19 0)
			(effects
				(font
					(size 1.27 1.27)
				)
				(justify left bottom)
				(hide yes)
			)
		)
		(property "Public" "False"
			(at 30.48 123.19 0)
			(effects
				(font
					(size 1.27 1.27)
				)
				(justify left bottom)
				(hide yes)
			)
		)
		(pin "2"
		)
		(pin "1"
		)
		(instances
			(project "com-express-7-baseboard"
				(path ""
					(reference "R183")
					(unit 1)
				)
			)
		)
	)
	(symbol
		(lib_id "antmicroCapacitors0402:C_100n_0402")
		(at 82.55 57.15 90)
		(unit 1)
		(exclude_from_sim no)
		(in_bom yes)
		(on_board yes)
		(dnp no)
		(fields_autoplaced yes)
		(property "Reference" "C11"
			(at 85.09 53.3336 90)
			(effects
				(font
					(size 1.27 1.27)
					(thickness 0.15)
				)
				(justify right)
			)
		)
		(property "Value" "C_100n_0402"
			(at 92.71 36.83 0)
			(effects
				(font
					(size 1.27 1.27)
					(thickness 0.15)
				)
				(justify left bottom)
				(hide yes)
			)
		)
		(property "Footprint" "antmicro-footprints:C_0402_1005Metric"
			(at 95.25 36.83 0)
			(effects
				(font
					(size 1.27 1.27)
					(thickness 0.15)
				)
				(justify left bottom)
				(hide yes)
			)
		)
		(property "Datasheet" "https://www.murata.com/products/productdetail?partno=GRM155R61H104KE14%23"
			(at 97.79 36.83 0)
			(effects
				(font
					(size 1.27 1.27)
					(thickness 0.15)
				)
				(justify left bottom)
				(hide yes)
			)
		)
		(property "Description" ""
			(at 82.55 57.15 0)
			(effects
				(font
					(size 1.27 1.27)
				)
				(hide yes)
			)
		)
		(property "MPN" "GRM155R61H104KE14D"
			(at 100.33 36.83 0)
			(effects
				(font
					(size 1.27 1.27)
					(thickness 0.15)
				)
				(justify left bottom)
				(hide yes)
			)
		)
		(property "Manufacturer" "Murata"
			(at 102.87 36.83 0)
			(effects
				(font
					(size 1.27 1.27)
					(thickness 0.15)
				)
				(justify left bottom)
				(hide yes)
			)
		)
		(property "License" "Apache-2.0"
			(at 105.41 36.83 0)
			(effects
				(font
					(size 1.27 1.27)
					(thickness 0.15)
				)
				(justify left bottom)
				(hide yes)
			)
		)
		(property "Author" "Antmicro"
			(at 107.95 36.83 0)
			(effects
				(font
					(size 1.27 1.27)
					(thickness 0.15)
				)
				(justify left bottom)
				(hide yes)
			)
		)
		(property "Val" "100n"
			(at 85.09 55.8736 90)
			(effects
				(font
					(size 1.27 1.27)
					(thickness 0.15)
				)
				(justify right)
			)
		)
		(property "Voltage" "50V"
			(at 110.49 36.83 0)
			(effects
				(font
					(size 1.27 1.27)
				)
				(justify left bottom)
				(hide yes)
			)
		)
		(property "Dielectric" "X5R"
			(at 113.03 36.83 0)
			(effects
				(font
					(size 1.27 1.27)
				)
				(justify left bottom)
				(hide yes)
			)
		)
		(property "Public" "False"
			(at 115.57 36.83 0)
			(effects
				(font
					(size 1.27 1.27)
				)
				(justify left bottom)
				(hide yes)
			)
		)
		(pin "1"
		)
		(pin "2"
		)
		(instances
			(project "com-express-7-baseboard"
				(path ""
					(reference "C11")
					(unit 1)
				)
			)
		)
	)
	(symbol
		(lib_id "antmicroTestPoints:TP_0.75mm_SMD")
		(at 107.95 106.68 180)
		(unit 1)
		(exclude_from_sim no)
		(in_bom no)
		(on_board yes)
		(dnp no)
		(property "Reference" "TP45"
			(at 101.6 106.68 0)
			(effects
				(font
					(size 1.27 1.27)
					(thickness 0.15)
				)
			)
		)
		(property "Value" "TP_0.75mm_SMD"
			(at 97.155 102.87 0)
			(effects
				(font
					(size 1.27 1.27)
					(thickness 0.15)
				)
				(justify left bottom)
				(hide yes)
			)
		)
		(property "Footprint" "antmicro-footprints:TP_SMD_0.75mm"
			(at 97.155 100.33 0)
			(effects
				(font
					(size 1.27 1.27)
					(thickness 0.15)
				)
				(justify left bottom)
				(hide yes)
			)
		)
		(property "Datasheet" ""
			(at 90.17 93.98 0)
			(effects
				(font
					(size 1.27 1.27)
					(thickness 0.15)
				)
				(justify left bottom)
				(hide yes)
			)
		)
		(property "Description" ""
			(at 107.95 106.68 0)
			(effects
				(font
					(size 1.27 1.27)
				)
				(hide yes)
			)
		)
		(property "MPN" ""
			(at 97.155 95.25 0)
			(effects
				(font
					(size 1.27 1.27)
					(thickness 0.15)
				)
				(justify left bottom)
				(hide yes)
			)
		)
		(property "Manufacturer" ""
			(at 97.155 100.33 0)
			(effects
				(font
					(size 1.27 1.27)
					(thickness 0.15)
				)
				(justify left bottom)
				(hide yes)
			)
		)
		(property "Author" "Antmicro"
			(at 97.155 97.79 0)
			(effects
				(font
					(size 1.27 1.27)
					(thickness 0.15)
				)
				(justify left bottom)
				(hide yes)
			)
		)
		(property "License" "Apache-2.0"
			(at 97.155 95.25 0)
			(effects
				(font
					(size 1.27 1.27)
					(thickness 0.15)
				)
				(justify left bottom)
				(hide yes)
			)
		)
		(property "Public" "False"
			(at 97.79 92.71 0)
			(effects
				(font
					(size 1.27 1.27)
				)
				(justify left bottom)
				(hide yes)
			)
		)
		(pin "1"
		)
		(instances
			(project "com-express-7-baseboard"
				(path ""
					(reference "TP45")
					(unit 1)
				)
			)
		)
	)
)
